FILE_TYPE = MACRO_DRAWING;
SET COLOR_WIRE YELLOW;
SET COLOR_PROP ORANGE;
SET COLOR_DOT WHITE;
SET COLOR_ARC YELLOW;
SET COLOR_BODY GREEN;
SET COLOR_NOTE PURPLE;
SET PROP_DISPLAY VALUE;
SET PAGE_NUMBER P171;
FORCEADD UNIVERSAL_GND..1
(-7925 4100);
FORCEPROP 3 LASTPIN (-7925 4150) SIG_NAME GND\g
J 0
(-7915 4160);
DISPLAY 0.659574 (-7915 4160);
PAINT MONO (-7915 4160);
DISPLAY INVISIBLE (-7915 4160);
FORCEPROP 2 LAST CDS_LIB pure_quanta_power
J 0
(-7925 4100);
DISPLAY INVISIBLE (-7925 4100);
FORCEPROP 1 LAST PATH I1
J 0
(-7850 4100);
DISPLAY 0.872340 (-7850 4100);
PAINT AQUA (-7850 4100);
DISPLAY INVISIBLE (-7850 4100);
FORCEPROP 1 LAST HDL_POWER GND
J 1
(-7900 4025);
DISPLAY 0.872340 (-7900 4025);
PAINT GREEN (-7900 4025);
DISPLAY INVISIBLE (-7900 4025);
FORCEADD Q_RES..1
(-7275 4350);
FORCEPROP 1 LAST LOCATION PR353
J 0
(-7300 4400);
DISPLAY 0.489362 (-7300 4400);
PAINT SKYBLUE (-7300 4400);
FORCEPROP 0 LAST $SEC 1
J 0
(-7275 4425);
DISPLAY 0.680851 (-7275 4425);
PAINT MONO (-7275 4425);
DISPLAY INVISIBLE (-7275 4425);
FORCEPROP 0 LAST CDS_SEC 1
J 0
(-7275 4425);
DISPLAY 1.021277 (-7275 4425);
DISPLAY INVISIBLE (-7275 4425);
FORCEPROP 1 LASTPIN (-7375 4350) $PN 1
J 0
(-7363 4362);
DISPLAY 0.489362 (-7363 4362);
PAINT MONO (-7363 4362);
FORCEPROP 1 LASTPIN (-7175 4350) $PN 2
J 0
(-7213 4362);
DISPLAY 0.489362 (-7213 4362);
PAINT MONO (-7213 4362);
FORCEPROP 1 LAST WATTAGE 1/16W
J 0
(-7175 4250);
DISPLAY 0.489362 (-7175 4250);
PAINT SKYBLUE (-7175 4250);
FORCEPROP 1 LAST MATERIAL EMPTY
J 0
(-7575 4250);
DISPLAY 0.489362 (-7575 4250);
PAINT RED (-7575 4250);
FORCEPROP 1 LAST TOLERANCE 1%
J 0
(-7150 4375);
DISPLAY 0.489362 (-7150 4375);
PAINT SKYBLUE (-7150 4375);
FORCEPROP 1 LAST VALUE 8.87K
J 2
(-7400 4375);
DISPLAY 0.489362 (-7400 4375);
PAINT SKYBLUE (-7400 4375);
FORCEPROP 1 LAST PART_NUMBER CS28872FB01
J 0
(-7575 4300);
DISPLAY 0.489362 (-7575 4300);
PAINT SKYBLUE (-7575 4300);
FORCEPROP 1 LAST PACK_TYPE 0402LF
J 0
(-7175 4300);
DISPLAY 0.489362 (-7175 4300);
PAINT SKYBLUE (-7175 4300);
FORCEPROP 2 LAST CDS_LIB pure_quanta
J 0
(-7275 4350);
DISPLAY INVISIBLE (-7275 4350);
FORCEPROP 1 LAST PATH I11
J 0
(-7325 4500);
DISPLAY 0.978723 (-7325 4500);
PAINT WHITE (-7325 4500);
DISPLAY INVISIBLE (-7325 4500);
FORCEADD UNIVERSAL_GND..1
(-5550 3925);
FORCEPROP 3 LASTPIN (-5550 3975) SIG_NAME GND\g
J 0
(-5540 3985);
DISPLAY 0.659574 (-5540 3985);
PAINT MONO (-5540 3985);
DISPLAY INVISIBLE (-5540 3985);
FORCEPROP 2 LAST CDS_LIB pure_quanta_power
J 0
(-5550 3925);
DISPLAY INVISIBLE (-5550 3925);
FORCEPROP 1 LAST PATH I15
J 0
(-5475 3925);
DISPLAY 0.872340 (-5475 3925);
PAINT AQUA (-5475 3925);
DISPLAY INVISIBLE (-5475 3925);
FORCEPROP 1 LAST HDL_POWER GND
J 1
(-5525 3850);
DISPLAY 0.872340 (-5525 3850);
PAINT GREEN (-5525 3850);
DISPLAY INVISIBLE (-5525 3850);
FORCEADD Q_RES..1
(-4025 3700);
FORCEPROP 1 LAST LOCATION PR355
J 0
(-4050 3750);
DISPLAY 0.489362 (-4050 3750);
PAINT SKYBLUE (-4050 3750);
FORCEPROP 0 LAST $SEC 1
J 0
(-4025 3775);
DISPLAY 0.680851 (-4025 3775);
PAINT MONO (-4025 3775);
DISPLAY INVISIBLE (-4025 3775);
FORCEPROP 0 LAST CDS_SEC 1
J 0
(-4025 3775);
DISPLAY 1.021277 (-4025 3775);
DISPLAY INVISIBLE (-4025 3775);
FORCEPROP 1 LASTPIN (-4125 3700) $PN 1
J 0
(-4113 3712);
DISPLAY 0.489362 (-4113 3712);
PAINT MONO (-4113 3712);
FORCEPROP 1 LASTPIN (-3925 3700) $PN 2
J 0
(-3963 3712);
DISPLAY 0.489362 (-3963 3712);
PAINT MONO (-3963 3712);
FORCEPROP 1 LAST WATTAGE 1/16W
J 0
(-3925 3650);
DISPLAY 0.489362 (-3925 3650);
PAINT SKYBLUE (-3925 3650);
FORCEPROP 1 LAST MATERIAL CHIP
J 0
(-4275 3600);
DISPLAY 0.489362 (-4275 3600);
PAINT SKYBLUE (-4275 3600);
FORCEPROP 1 LAST TOLERANCE 5%
J 0
(-3900 3725);
DISPLAY 0.489362 (-3900 3725);
PAINT SKYBLUE (-3900 3725);
FORCEPROP 1 LAST VALUE 0
J 2
(-4150 3725);
DISPLAY 0.489362 (-4150 3725);
PAINT SKYBLUE (-4150 3725);
FORCEPROP 1 LAST PART_NUMBER CS00002JB38
J 0
(-4275 3650);
DISPLAY 0.489362 (-4275 3650);
PAINT SKYBLUE (-4275 3650);
FORCEPROP 1 LAST PACK_TYPE 0402LF
J 0
(-3925 3600);
DISPLAY 0.489362 (-3925 3600);
PAINT SKYBLUE (-3925 3600);
FORCEPROP 2 LAST CDS_LIB pure_quanta
J 0
(-4025 3700);
DISPLAY INVISIBLE (-4025 3700);
FORCEPROP 1 LAST PATH I17
J 0
(-4075 3850);
DISPLAY 0.978723 (-4075 3850);
PAINT WHITE (-4075 3850);
DISPLAY INVISIBLE (-4075 3850);
FORCEADD Q_RES..1
(-4675 5000);
FORCEPROP 1 LAST LOCATION PR354
J 0
(-4700 5050);
DISPLAY 0.489362 (-4700 5050);
PAINT SKYBLUE (-4700 5050);
FORCEPROP 0 LAST $SEC 1
J 0
(-4650 5075);
DISPLAY 0.680851 (-4650 5075);
PAINT MONO (-4650 5075);
DISPLAY INVISIBLE (-4650 5075);
FORCEPROP 0 LAST CDS_SEC 1
J 0
(-4650 5075);
DISPLAY 1.021277 (-4650 5075);
DISPLAY INVISIBLE (-4650 5075);
FORCEPROP 1 LASTPIN (-4775 5000) $PN 1
J 0
(-4763 5012);
DISPLAY 0.489362 (-4763 5012);
PAINT MONO (-4763 5012);
FORCEPROP 1 LASTPIN (-4575 5000) $PN 2
J 0
(-4613 5012);
DISPLAY 0.489362 (-4613 5012);
PAINT MONO (-4613 5012);
FORCEPROP 1 LAST PACK_TYPE 0402LF
J 0
(-4575 4900);
DISPLAY 0.489362 (-4575 4900);
PAINT SKYBLUE (-4575 4900);
FORCEPROP 1 LAST TOLERANCE 1%
J 0
(-4575 5025);
DISPLAY 0.489362 (-4575 5025);
PAINT SKYBLUE (-4575 5025);
FORCEPROP 1 LAST MATERIAL CHIP
J 0
(-4925 4900);
DISPLAY 0.489362 (-4925 4900);
PAINT SKYBLUE (-4925 4900);
FORCEPROP 1 LAST WATTAGE 1/16W
J 0
(-4575 4950);
DISPLAY 0.489362 (-4575 4950);
PAINT SKYBLUE (-4575 4950);
FORCEPROP 1 LAST VALUE 4.7
J 2
(-4775 5025);
DISPLAY 0.489362 (-4775 5025);
PAINT SKYBLUE (-4775 5025);
FORCEPROP 1 LAST PART_NUMBER CS-4702FB19
J 0
(-4925 4950);
DISPLAY 0.489362 (-4925 4950);
PAINT SKYBLUE (-4925 4950);
FORCEPROP 1 LAST PATH I18
J 0
(-4725 5150);
DISPLAY 0.978723 (-4725 5150);
PAINT WHITE (-4725 5150);
DISPLAY INVISIBLE (-4725 5150);
FORCEPROP 2 LAST CDS_LIB pure_quanta
J 0
(-4675 5000);
DISPLAY INVISIBLE (-4675 5000);
FORCEADD Q_CAP..1
(-4975 5525);
FORCEPROP 1 LAST LOCATION PC570_5
J 0
(-4925 5625);
DISPLAY 0.489362 (-4925 5625);
PAINT SKYBLUE (-4925 5625);
FORCEPROP 0 LAST $SEC 1
J 0
(-4925 5650);
DISPLAY 0.680851 (-4925 5650);
PAINT MONO (-4925 5650);
DISPLAY INVISIBLE (-4925 5650);
FORCEPROP 0 LAST CDS_SEC 1
J 0
(-4925 5650);
DISPLAY 1.021277 (-4925 5650);
DISPLAY INVISIBLE (-4925 5650);
FORCEPROP 1 LASTPIN (-4975 5625) $PN 1
J 0
(-4965 5605);
DISPLAY 0.489362 (-4965 5605);
PAINT MONO (-4965 5605);
FORCEPROP 1 LASTPIN (-4975 5425) $PN 2
J 0
(-4965 5405);
DISPLAY 0.489362 (-4965 5405);
PAINT MONO (-4965 5405);
FORCEPROP 1 LAST MATERIAL X6S
J 0
(-4925 5425);
DISPLAY 0.489362 (-4925 5425);
PAINT SKYBLUE (-4925 5425);
FORCEPROP 1 LAST TOLERANCE 10%
J 0
(-4925 5475);
DISPLAY 0.489362 (-4925 5475);
PAINT SKYBLUE (-4925 5475);
FORCEPROP 1 LAST VALUE 1UF
J 0
(-4925 5575);
DISPLAY 0.489362 (-4925 5575);
PAINT SKYBLUE (-4925 5575);
FORCEPROP 1 LAST PART_NUMBER CH5104KEB02
J 0
(-4925 5375);
DISPLAY 0.489362 (-4925 5375);
PAINT SKYBLUE (-4925 5375);
FORCEPROP 1 LAST VOLTAGE 25V
J 0
(-4925 5525);
DISPLAY 0.489362 (-4925 5525);
PAINT SKYBLUE (-4925 5525);
FORCEPROP 1 LAST PACK_TYPE C0402
J 0
(-4925 5325);
DISPLAY 0.489362 (-4925 5325);
PAINT SKYBLUE (-4925 5325);
FORCEPROP 2 LAST CDS_LIB pure_quanta
J 0
(-4975 5525);
DISPLAY INVISIBLE (-4975 5525);
FORCEPROP 1 LAST PATH I19
J 0
(-4925 5675);
DISPLAY 0.978723 (-4925 5675);
PAINT WHITE (-4925 5675);
DISPLAY INVISIBLE (-4925 5675);
FORCEADD Q_CAP..1
(-7925 4375);
FORCEPROP 1 LAST LOCATION PC566_5
J 0
(-7875 4475);
DISPLAY 0.489362 (-7875 4475);
PAINT SKYBLUE (-7875 4475);
FORCEPROP 0 LAST $SEC 1
J 0
(-7875 4500);
DISPLAY 0.680851 (-7875 4500);
PAINT MONO (-7875 4500);
DISPLAY INVISIBLE (-7875 4500);
FORCEPROP 0 LAST CDS_SEC 1
J 0
(-7875 4500);
DISPLAY 1.021277 (-7875 4500);
DISPLAY INVISIBLE (-7875 4500);
FORCEPROP 1 LASTPIN (-7925 4475) $PN 1
J 0
(-7915 4455);
DISPLAY 0.489362 (-7915 4455);
PAINT MONO (-7915 4455);
FORCEPROP 1 LASTPIN (-7925 4275) $PN 2
J 0
(-7915 4255);
DISPLAY 0.489362 (-7915 4255);
PAINT MONO (-7915 4255);
FORCEPROP 1 LAST MATERIAL X7R
J 0
(-7875 4275);
DISPLAY 0.489362 (-7875 4275);
PAINT SKYBLUE (-7875 4275);
FORCEPROP 1 LAST TOLERANCE 10%
J 0
(-7875 4325);
DISPLAY 0.489362 (-7875 4325);
PAINT SKYBLUE (-7875 4325);
FORCEPROP 1 LAST VALUE 0.1UF
J 0
(-7875 4425);
DISPLAY 0.489362 (-7875 4425);
PAINT SKYBLUE (-7875 4425);
FORCEPROP 1 LAST PART_NUMBER CH4104K1B00
J 0
(-7875 4225);
DISPLAY 0.489362 (-7875 4225);
PAINT SKYBLUE (-7875 4225);
FORCEPROP 1 LAST VOLTAGE 25V
J 0
(-7875 4375);
DISPLAY 0.489362 (-7875 4375);
PAINT SKYBLUE (-7875 4375);
FORCEPROP 1 LAST PACK_TYPE 0402
J 0
(-7875 4175);
DISPLAY 0.489362 (-7875 4175);
PAINT SKYBLUE (-7875 4175);
FORCEPROP 2 LAST CDS_LIB pure_quanta
J 0
(-7925 4375);
DISPLAY INVISIBLE (-7925 4375);
FORCEPROP 1 LAST PATH I2
J 0
(-7875 4525);
DISPLAY 0.978723 (-7875 4525);
PAINT WHITE (-7875 4525);
DISPLAY INVISIBLE (-7875 4525);
FORCEADD Q_CAP..1
(-4650 5525);
FORCEPROP 1 LAST LOCATION PC571_5
J 0
(-4600 5625);
DISPLAY 0.489362 (-4600 5625);
PAINT SKYBLUE (-4600 5625);
FORCEPROP 0 LAST $SEC 1
J 0
(-4600 5650);
DISPLAY 0.680851 (-4600 5650);
PAINT MONO (-4600 5650);
DISPLAY INVISIBLE (-4600 5650);
FORCEPROP 0 LAST CDS_SEC 1
J 0
(-4600 5650);
DISPLAY 1.021277 (-4600 5650);
DISPLAY INVISIBLE (-4600 5650);
FORCEPROP 1 LASTPIN (-4650 5625) $PN 1
J 0
(-4640 5605);
DISPLAY 0.489362 (-4640 5605);
PAINT MONO (-4640 5605);
FORCEPROP 1 LASTPIN (-4650 5425) $PN 2
J 0
(-4640 5405);
DISPLAY 0.489362 (-4640 5405);
PAINT MONO (-4640 5405);
FORCEPROP 1 LAST MATERIAL X6S
J 0
(-4600 5425);
DISPLAY 0.489362 (-4600 5425);
PAINT SKYBLUE (-4600 5425);
FORCEPROP 1 LAST TOLERANCE 10%
J 0
(-4600 5475);
DISPLAY 0.489362 (-4600 5475);
PAINT SKYBLUE (-4600 5475);
FORCEPROP 1 LAST VALUE 10UF
J 0
(-4600 5575);
DISPLAY 0.489362 (-4600 5575);
PAINT SKYBLUE (-4600 5575);
FORCEPROP 1 LAST PART_NUMBER CH6104KEA00
J 0
(-4600 5375);
DISPLAY 0.489362 (-4600 5375);
PAINT SKYBLUE (-4600 5375);
FORCEPROP 1 LAST VOLTAGE 25V
J 0
(-4600 5525);
DISPLAY 0.489362 (-4600 5525);
PAINT SKYBLUE (-4600 5525);
FORCEPROP 1 LAST PACK_TYPE C0805
J 0
(-4600 5325);
DISPLAY 0.489362 (-4600 5325);
PAINT SKYBLUE (-4600 5325);
FORCEPROP 2 LAST CDS_LIB pure_quanta
J 0
(-4650 5525);
DISPLAY INVISIBLE (-4650 5525);
FORCEPROP 1 LAST PATH I20
J 0
(-4600 5675);
DISPLAY 0.978723 (-4600 5675);
PAINT WHITE (-4600 5675);
DISPLAY INVISIBLE (-4600 5675);
FORCEADD Q_CAP..1
(-4300 5525);
FORCEPROP 1 LAST LOCATION PC572_5
J 0
(-4250 5625);
DISPLAY 0.489362 (-4250 5625);
PAINT SKYBLUE (-4250 5625);
FORCEPROP 0 LAST $SEC 1
J 0
(-4250 5650);
DISPLAY 0.680851 (-4250 5650);
PAINT MONO (-4250 5650);
DISPLAY INVISIBLE (-4250 5650);
FORCEPROP 0 LAST CDS_SEC 1
J 0
(-4250 5650);
DISPLAY 1.021277 (-4250 5650);
DISPLAY INVISIBLE (-4250 5650);
FORCEPROP 1 LASTPIN (-4300 5625) $PN 1
J 0
(-4290 5605);
DISPLAY 0.489362 (-4290 5605);
PAINT MONO (-4290 5605);
FORCEPROP 1 LASTPIN (-4300 5425) $PN 2
J 0
(-4290 5405);
DISPLAY 0.489362 (-4290 5405);
PAINT MONO (-4290 5405);
FORCEPROP 1 LAST TOLERANCE 10%
J 0
(-4250 5475);
DISPLAY 0.489362 (-4250 5475);
PAINT SKYBLUE (-4250 5475);
FORCEPROP 1 LAST VALUE 10UF
J 0
(-4250 5575);
DISPLAY 0.489362 (-4250 5575);
PAINT SKYBLUE (-4250 5575);
FORCEPROP 1 LAST VOLTAGE 25V
J 0
(-4250 5525);
DISPLAY 0.489362 (-4250 5525);
PAINT SKYBLUE (-4250 5525);
FORCEPROP 1 LAST PACK_TYPE C0805
J 0
(-4250 5325);
DISPLAY 0.489362 (-4250 5325);
PAINT SKYBLUE (-4250 5325);
FORCEPROP 1 LAST MATERIAL X6S
J 0
(-4250 5425);
DISPLAY 0.489362 (-4250 5425);
PAINT SKYBLUE (-4250 5425);
FORCEPROP 1 LAST PART_NUMBER CH6104KEA00
J 0
(-4250 5375);
DISPLAY 0.489362 (-4250 5375);
PAINT SKYBLUE (-4250 5375);
FORCEPROP 2 LAST CDS_LIB pure_quanta
J 0
(-4300 5525);
DISPLAY INVISIBLE (-4300 5525);
FORCEPROP 1 LAST PATH I21
J 0
(-4250 5675);
DISPLAY 0.978723 (-4250 5675);
PAINT WHITE (-4250 5675);
DISPLAY INVISIBLE (-4250 5675);
FORCEADD Q_CAP..1
(-3675 4875);
FORCEPROP 1 LAST LOCATION PC574
J 0
(-3625 5000);
DISPLAY 0.489362 (-3625 5000);
PAINT SKYBLUE (-3625 5000);
FORCEPROP 0 LAST $SEC 1
J 0
(-3625 5025);
DISPLAY 0.680851 (-3625 5025);
PAINT MONO (-3625 5025);
DISPLAY INVISIBLE (-3625 5025);
FORCEPROP 0 LAST CDS_SEC 1
J 0
(-3625 5025);
DISPLAY 1.021277 (-3625 5025);
DISPLAY INVISIBLE (-3625 5025);
FORCEPROP 1 LASTPIN (-3675 4975) $PN 1
J 0
(-3665 4955);
DISPLAY 0.489362 (-3665 4955);
PAINT MONO (-3665 4955);
FORCEPROP 1 LASTPIN (-3675 4775) $PN 2
J 0
(-3665 4755);
DISPLAY 0.489362 (-3665 4755);
PAINT MONO (-3665 4755);
FORCEPROP 1 LAST MATERIAL X7R
J 0
(-3625 4800);
DISPLAY 0.489362 (-3625 4800);
PAINT SKYBLUE (-3625 4800);
FORCEPROP 1 LAST TOLERANCE 10%
J 0
(-3625 4850);
DISPLAY 0.489362 (-3625 4850);
PAINT SKYBLUE (-3625 4850);
FORCEPROP 1 LAST VALUE 0.22UF
J 0
(-3625 4950);
DISPLAY 0.489362 (-3625 4950);
PAINT SKYBLUE (-3625 4950);
FORCEPROP 1 LAST PART_NUMBER CH4223K1B00
J 0
(-3625 4750);
DISPLAY 0.489362 (-3625 4750);
PAINT SKYBLUE (-3625 4750);
FORCEPROP 1 LAST VOLTAGE 16V
J 0
(-3625 4900);
DISPLAY 0.489362 (-3625 4900);
PAINT SKYBLUE (-3625 4900);
FORCEPROP 1 LAST PACK_TYPE 0402
J 0
(-3625 4700);
DISPLAY 0.489362 (-3625 4700);
PAINT SKYBLUE (-3625 4700);
FORCEPROP 2 LAST CDS_LIB pure_quanta
J 0
(-3675 4875);
DISPLAY INVISIBLE (-3675 4875);
FORCEPROP 1 LAST PATH I22
J 0
(-3625 5025);
DISPLAY 0.978723 (-3625 5025);
PAINT WHITE (-3625 5025);
DISPLAY INVISIBLE (-3625 5025);
FORCEADD Q_INDUCTOR4P_14..1
(-2875 4525);
FORCEPROP 1 LAST LOCATION PL61
J 0
(-3100 4780);
DISPLAY 0.489362 (-3100 4780);
PAINT SKYBLUE (-3100 4780);
FORCEPROP 0 LAST $SEC 1
J 0
(-3100 4925);
DISPLAY 0.680851 (-3100 4925);
PAINT MONO (-3100 4925);
DISPLAY INVISIBLE (-3100 4925);
FORCEPROP 0 LAST CDS_SEC 1
J 0
(-3100 4925);
DISPLAY 1.021277 (-3100 4925);
DISPLAY INVISIBLE (-3100 4925);
FORCEPROP 0 LASTPIN (-3275 4650) $PN 1
J 2
(-3285 4660);
DISPLAY 0.489362 (-3285 4660);
PAINT MONO (-3285 4660);
FORCEPROP 0 LASTPIN (-3275 4400) $PN 2
J 2
(-3285 4410);
DISPLAY 0.489362 (-3285 4410);
PAINT MONO (-3285 4410);
FORCEPROP 0 LASTPIN (-2475 4400) $PN 3
J 0
(-2465 4410);
DISPLAY 0.489362 (-2465 4410);
PAINT MONO (-2465 4410);
FORCEPROP 0 LASTPIN (-2475 4650) $PN 4
J 0
(-2465 4660);
DISPLAY 0.489362 (-2465 4660);
PAINT MONO (-2465 4660);
FORCEPROP 1 LAST PART_NUMBER CV+15^0TZ04
J 0
(-3100 4685);
DISPLAY 0.489362 (-3100 4685);
PAINT SKYBLUE (-3100 4685);
FORCEPROP 1 LAST MATERIAL IND
J 0
(-3100 4735);
DISPLAY 0.489362 (-3100 4735);
PAINT SKYBLUE (-3100 4735);
FORCEPROP 2 LAST PART_TYPE SMLF
J 0
(-3100 4875);
DISPLAY 1.021277 (-3100 4875);
FORCEPROP 2 LAST VALUE 150NH
J 0
(-3100 4825);
DISPLAY 0.489362 (-3100 4825);
PAINT SKYBLUE (-3100 4825);
FORCEPROP 2 LAST CDS_LIB pure_quanta
J 0
(-2875 4525);
DISPLAY INVISIBLE (-2875 4525);
FORCEPROP 1 LAST NEEDS_NO_SIZE TRUE
J 0
(-2875 4525);
DISPLAY 0.468085 (-2875 4525);
PAINT GREEN (-2875 4525);
DISPLAY INVISIBLE (-2875 4525);
FORCEPROP 1 LAST PATH I23
J 0
(-2675 4680);
DISPLAY 0.723404 (-2675 4680);
PAINT GREEN (-2675 4680);
DISPLAY INVISIBLE (-2675 4680);
FORCEADD UNIVERSAL_GND..1
(-3950 5175);
FORCEPROP 3 LASTPIN (-3950 5225) SIG_NAME GND\g
J 0
(-3940 5235);
DISPLAY 0.659574 (-3940 5235);
PAINT MONO (-3940 5235);
DISPLAY INVISIBLE (-3940 5235);
FORCEPROP 2 LAST CDS_LIB pure_quanta_power
J 0
(-3950 5175);
DISPLAY INVISIBLE (-3950 5175);
FORCEPROP 1 LAST PATH I24
J 0
(-3875 5175);
DISPLAY 0.872340 (-3875 5175);
PAINT AQUA (-3875 5175);
DISPLAY INVISIBLE (-3875 5175);
FORCEPROP 1 LAST HDL_POWER GND
J 1
(-3925 5100);
DISPLAY 0.872340 (-3925 5100);
PAINT GREEN (-3925 5100);
DISPLAY INVISIBLE (-3925 5100);
FORCEADD Q_CAP..1
(-3950 5525);
FORCEPROP 1 LAST LOCATION PC573_5
J 0
(-3900 5625);
DISPLAY 0.489362 (-3900 5625);
PAINT SKYBLUE (-3900 5625);
FORCEPROP 0 LAST $SEC 1
J 0
(-3900 5650);
DISPLAY 0.680851 (-3900 5650);
PAINT MONO (-3900 5650);
DISPLAY INVISIBLE (-3900 5650);
FORCEPROP 0 LAST CDS_SEC 1
J 0
(-3900 5650);
DISPLAY 1.021277 (-3900 5650);
DISPLAY INVISIBLE (-3900 5650);
FORCEPROP 1 LASTPIN (-3950 5625) $PN 1
J 0
(-3940 5605);
DISPLAY 0.489362 (-3940 5605);
PAINT MONO (-3940 5605);
FORCEPROP 1 LASTPIN (-3950 5425) $PN 2
J 0
(-3940 5405);
DISPLAY 0.489362 (-3940 5405);
PAINT MONO (-3940 5405);
FORCEPROP 1 LAST PART_NUMBER CH6104KEA00
J 0
(-3900 5375);
DISPLAY 0.489362 (-3900 5375);
PAINT SKYBLUE (-3900 5375);
FORCEPROP 1 LAST MATERIAL X6S
J 0
(-3900 5425);
DISPLAY 0.489362 (-3900 5425);
PAINT SKYBLUE (-3900 5425);
FORCEPROP 1 LAST TOLERANCE 10%
J 0
(-3900 5475);
DISPLAY 0.489362 (-3900 5475);
PAINT SKYBLUE (-3900 5475);
FORCEPROP 1 LAST VALUE 10UF
J 0
(-3900 5575);
DISPLAY 0.489362 (-3900 5575);
PAINT SKYBLUE (-3900 5575);
FORCEPROP 1 LAST VOLTAGE 25V
J 0
(-3900 5525);
DISPLAY 0.489362 (-3900 5525);
PAINT SKYBLUE (-3900 5525);
FORCEPROP 1 LAST PACK_TYPE C0805
J 0
(-3900 5325);
DISPLAY 0.489362 (-3900 5325);
PAINT SKYBLUE (-3900 5325);
FORCEPROP 2 LAST CDS_LIB pure_quanta
J 0
(-3950 5525);
DISPLAY INVISIBLE (-3950 5525);
FORCEPROP 1 LAST PATH I25
J 0
(-3900 5675);
DISPLAY 0.978723 (-3900 5675);
PAINT WHITE (-3900 5675);
DISPLAY INVISIBLE (-3900 5675);
FORCEADD VCC_CORE..1
(-3950 5825);
FORCEPROP 3 LASTPIN (-3950 5775) SIG_NAME SW_P12V_STBY_PVDDCR_CPU0_P0_FLT\g
J 0
(-3940 5785);
DISPLAY 0.659574 (-3940 5785);
PAINT MONO (-3940 5785);
DISPLAY INVISIBLE (-3940 5785);
FORCEPROP 1 LAST HDL_POWER SW_P12V_STBY_PVDDCR_CPU0_P0_FLT
J 1
(-3950 5875);
DISPLAY 0.489362 (-3950 5875);
PAINT GREEN (-3950 5875);
FORCEPROP 2 LAST CDS_LIB pure_quanta_power
J 0
(-3950 5825);
DISPLAY INVISIBLE (-3950 5825);
FORCEPROP 1 LAST PATH I26
J 0
(-3900 5850);
DISPLAY 0.872340 (-3900 5850);
PAINT AQUA (-3900 5850);
DISPLAY INVISIBLE (-3900 5850);
FORCEADD OFFPAGE..3
(-1975 4400);
FORCEPROP 2 LAST $XR0 170 
J 0
(-1671 4400);
DISPLAY 0.638298 (-1671 4400);
PAINT MONO (-1671 4400);
FORCEPROP 2 LAST PATH I27
J 0
(-1775 4475);
DISPLAY 1.021277 (-1775 4475);
DISPLAY INVISIBLE (-1775 4475);
FORCEPROP 1 LAST COMMENT_BODY TRUE
J 0
(-2025 4300);
DISPLAY 0.872340 (-2025 4300);
PAINT GREEN (-2025 4300);
DISPLAY INVISIBLE (-2025 4300);
FORCEPROP 1 LAST OFFPAGE TRUE
J 0
(-1650 4275);
DISPLAY 0.872340 (-1650 4275);
PAINT GREEN (-1650 4275);
DISPLAY INVISIBLE (-1650 4275);
FORCEPROP 2 LAST CDS_LIB standard
J 2
(-1975 4400);
DISPLAY INVISIBLE (-1975 4400);
FORCEADD OFFPAGE..1
(-8150 4550);
FORCEPROP 2 LAST $XR5 175 
J 0
(-9032 4550);
DISPLAY 0.638298 (-9032 4550);
PAINT MONO (-9032 4550);
FORCEPROP 2 LAST $XR4 174 
J 0
(-8912 4550);
DISPLAY 0.638298 (-8912 4550);
PAINT MONO (-8912 4550);
FORCEPROP 2 LAST $XR3 172 
J 0
(-8792 4550);
DISPLAY 0.638298 (-8792 4550);
PAINT MONO (-8792 4550);
FORCEPROP 2 LAST $XR2 171 
J 0
(-8672 4550);
DISPLAY 0.638298 (-8672 4550);
PAINT MONO (-8672 4550);
FORCEPROP 2 LAST $XR1 170 
J 0
(-8552 4550);
DISPLAY 0.638298 (-8552 4550);
PAINT MONO (-8552 4550);
FORCEPROP 2 LAST $XR0 169 
J 0
(-8432 4550);
DISPLAY 0.638298 (-8432 4550);
PAINT MONO (-8432 4550);
FORCEPROP 2 LAST CDS_LIB standard
J 0
(-8150 4550);
DISPLAY INVISIBLE (-8150 4550);
FORCEPROP 1 LAST OFFPAGE TRUE
J 0
(-7825 4425);
DISPLAY 0.872340 (-7825 4425);
PAINT GREEN (-7825 4425);
DISPLAY INVISIBLE (-7825 4425);
FORCEPROP 1 LAST COMMENT_BODY TRUE
J 0
(-8025 4450);
DISPLAY 0.872340 (-8025 4450);
PAINT GREEN (-8025 4450);
DISPLAY INVISIBLE (-8025 4450);
FORCEPROP 2 LAST PATH I3
J 0
(-8100 4625);
DISPLAY 1.021277 (-8100 4625);
DISPLAY INVISIBLE (-8100 4625);
FORCEADD Q_CAP..1
(-1475 4475);
FORCEPROP 1 LAST LOCATION PC575_5
J 0
(-1425 4575);
DISPLAY 0.489362 (-1425 4575);
PAINT SKYBLUE (-1425 4575);
FORCEPROP 0 LAST $SEC 1
J 0
(-1425 4600);
DISPLAY 0.680851 (-1425 4600);
PAINT MONO (-1425 4600);
DISPLAY INVISIBLE (-1425 4600);
FORCEPROP 0 LAST CDS_SEC 1
J 0
(-1425 4600);
DISPLAY 1.021277 (-1425 4600);
DISPLAY INVISIBLE (-1425 4600);
FORCEPROP 1 LASTPIN (-1475 4575) $PN 1
J 0
(-1465 4555);
DISPLAY 0.489362 (-1465 4555);
PAINT MONO (-1465 4555);
FORCEPROP 1 LASTPIN (-1475 4375) $PN 2
J 0
(-1465 4355);
DISPLAY 0.489362 (-1465 4355);
PAINT MONO (-1465 4355);
FORCEPROP 1 LAST MATERIAL X6S
J 0
(-1425 4375);
DISPLAY 0.489362 (-1425 4375);
PAINT SKYBLUE (-1425 4375);
FORCEPROP 1 LAST TOLERANCE 20%
J 0
(-1425 4425);
DISPLAY 0.489362 (-1425 4425);
PAINT SKYBLUE (-1425 4425);
FORCEPROP 1 LAST VALUE 22UF
J 0
(-1425 4525);
DISPLAY 0.489362 (-1425 4525);
PAINT SKYBLUE (-1425 4525);
FORCEPROP 1 LAST PART_NUMBER TMP_QCH622KMEA01
J 0
(-1425 4325);
DISPLAY 0.489362 (-1425 4325);
PAINT SKYBLUE (-1425 4325);
FORCEPROP 1 LAST VOLTAGE 4V
J 0
(-1425 4475);
DISPLAY 0.489362 (-1425 4475);
PAINT SKYBLUE (-1425 4475);
FORCEPROP 1 LAST PACK_TYPE 0805
J 0
(-1425 4275);
DISPLAY 0.489362 (-1425 4275);
PAINT SKYBLUE (-1425 4275);
FORCEPROP 2 LAST CDS_LIB pure_quanta
J 0
(-1475 4475);
DISPLAY INVISIBLE (-1475 4475);
FORCEPROP 1 LAST PATH I30
J 0
(-1425 4625);
DISPLAY 0.978723 (-1425 4625);
PAINT WHITE (-1425 4625);
DISPLAY INVISIBLE (-1425 4625);
FORCEADD UNIVERSAL_GND..1
(-1050 4125);
FORCEPROP 3 LASTPIN (-1050 4175) SIG_NAME GND\g
J 0
(-1040 4185);
DISPLAY 0.659574 (-1040 4185);
PAINT MONO (-1040 4185);
DISPLAY INVISIBLE (-1040 4185);
FORCEPROP 2 LAST CDS_LIB pure_quanta_power
J 0
(-1050 4125);
DISPLAY INVISIBLE (-1050 4125);
FORCEPROP 1 LAST PATH I31
J 0
(-975 4125);
DISPLAY 0.872340 (-975 4125);
PAINT AQUA (-975 4125);
DISPLAY INVISIBLE (-975 4125);
FORCEPROP 1 LAST HDL_POWER GND
J 1
(-1025 4050);
DISPLAY 0.872340 (-1025 4050);
PAINT GREEN (-1025 4050);
DISPLAY INVISIBLE (-1025 4050);
FORCEADD Q_CAP..1
(-1050 4475);
FORCEPROP 1 LAST LOCATION PC576_5
J 0
(-1000 4575);
DISPLAY 0.489362 (-1000 4575);
PAINT SKYBLUE (-1000 4575);
FORCEPROP 0 LAST $SEC 1
J 0
(-1000 4600);
DISPLAY 0.680851 (-1000 4600);
PAINT MONO (-1000 4600);
DISPLAY INVISIBLE (-1000 4600);
FORCEPROP 0 LAST CDS_SEC 1
J 0
(-1000 4600);
DISPLAY 1.021277 (-1000 4600);
DISPLAY INVISIBLE (-1000 4600);
FORCEPROP 1 LASTPIN (-1050 4575) $PN 1
J 0
(-1040 4555);
DISPLAY 0.489362 (-1040 4555);
PAINT MONO (-1040 4555);
FORCEPROP 1 LASTPIN (-1050 4375) $PN 2
J 0
(-1040 4355);
DISPLAY 0.489362 (-1040 4355);
PAINT MONO (-1040 4355);
FORCEPROP 1 LAST MATERIAL X6S
J 0
(-1000 4375);
DISPLAY 0.489362 (-1000 4375);
PAINT SKYBLUE (-1000 4375);
FORCEPROP 1 LAST TOLERANCE 20%
J 0
(-1000 4425);
DISPLAY 0.489362 (-1000 4425);
PAINT SKYBLUE (-1000 4425);
FORCEPROP 1 LAST VALUE 22UF
J 0
(-1000 4525);
DISPLAY 0.489362 (-1000 4525);
PAINT SKYBLUE (-1000 4525);
FORCEPROP 1 LAST PART_NUMBER TMP_QCH622KMEA01
J 0
(-1000 4325);
DISPLAY 0.489362 (-1000 4325);
PAINT SKYBLUE (-1000 4325);
FORCEPROP 1 LAST VOLTAGE 4V
J 0
(-1000 4475);
DISPLAY 0.489362 (-1000 4475);
PAINT SKYBLUE (-1000 4475);
FORCEPROP 1 LAST PACK_TYPE 0805
J 0
(-1000 4275);
DISPLAY 0.489362 (-1000 4275);
PAINT SKYBLUE (-1000 4275);
FORCEPROP 2 LAST CDS_LIB pure_quanta
J 0
(-1050 4475);
DISPLAY INVISIBLE (-1050 4475);
FORCEPROP 1 LAST PATH I32
J 0
(-1000 4625);
DISPLAY 0.978723 (-1000 4625);
PAINT WHITE (-1000 4625);
DISPLAY INVISIBLE (-1000 4625);
FORCEADD VCC_CORE..1
(-1050 4800);
FORCEPROP 3 LASTPIN (-1050 4750) SIG_NAME PVDDCR_CPU0_P0\g
J 0
(-1040 4760);
DISPLAY 0.659574 (-1040 4760);
PAINT MONO (-1040 4760);
DISPLAY INVISIBLE (-1040 4760);
FORCEPROP 1 LAST HDL_POWER PVDDCR_CPU0_P0
J 1
(-1050 4850);
DISPLAY 0.489362 (-1050 4850);
PAINT GREEN (-1050 4850);
FORCEPROP 2 LAST CDS_LIB pure_quanta_power
J 0
(-1050 4800);
DISPLAY INVISIBLE (-1050 4800);
FORCEPROP 1 LAST PATH I33
J 0
(-1000 4825);
DISPLAY 0.872340 (-1000 4825);
PAINT AQUA (-1000 4825);
DISPLAY INVISIBLE (-1000 4825);
FORCEADD OFFPAGE..3
R 2
(-3775 4400);
FORCEPROP 2 LAST $XR0 172 
J 0
(-4085 4400);
DISPLAY 0.638298 (-4085 4400);
PAINT MONO (-4085 4400);
FORCEPROP 2 LAST PATH I34
J 0
(-3725 4475);
DISPLAY 1.021277 (-3725 4475);
DISPLAY INVISIBLE (-3725 4475);
FORCEPROP 1 LAST COMMENT_BODY TRUE
J 2
(-3725 4300);
DISPLAY 0.872340 (-3725 4300);
PAINT GREEN (-3725 4300);
DISPLAY INVISIBLE (-3725 4300);
FORCEPROP 1 LAST OFFPAGE TRUE
J 2
(-4100 4275);
DISPLAY 0.872340 (-4100 4275);
PAINT GREEN (-4100 4275);
DISPLAY INVISIBLE (-4100 4275);
FORCEPROP 2 LAST CDS_LIB standard
J 2
(-3775 4400);
DISPLAY INVISIBLE (-3775 4400);
FORCEADD Q_CAP..1
(-5350 5525);
FORCEPROP 1 LAST LOCATION PC569_5
J 0
(-5300 5625);
DISPLAY 0.489362 (-5300 5625);
PAINT SKYBLUE (-5300 5625);
FORCEPROP 0 LAST $SEC 1
J 0
(-5300 5675);
DISPLAY 0.680851 (-5300 5675);
PAINT MONO (-5300 5675);
DISPLAY INVISIBLE (-5300 5675);
FORCEPROP 0 LAST CDS_SEC 1
J 0
(-5300 5675);
DISPLAY 1.021277 (-5300 5675);
DISPLAY INVISIBLE (-5300 5675);
FORCEPROP 1 LASTPIN (-5350 5625) $PN 1
J 0
(-5340 5605);
DISPLAY 0.489362 (-5340 5605);
PAINT MONO (-5340 5605);
FORCEPROP 1 LASTPIN (-5350 5425) $PN 2
J 0
(-5340 5405);
DISPLAY 0.489362 (-5340 5405);
PAINT MONO (-5340 5405);
FORCEPROP 1 LAST MATERIAL X7R
J 0
(-5300 5425);
DISPLAY 0.489362 (-5300 5425);
PAINT SKYBLUE (-5300 5425);
FORCEPROP 1 LAST TOLERANCE 10%
J 0
(-5300 5475);
DISPLAY 0.489362 (-5300 5475);
PAINT SKYBLUE (-5300 5475);
FORCEPROP 1 LAST VALUE 0.1UF
J 0
(-5300 5575);
DISPLAY 0.489362 (-5300 5575);
PAINT SKYBLUE (-5300 5575);
FORCEPROP 1 LAST PART_NUMBER CH4104K1B00
J 0
(-5300 5375);
DISPLAY 0.489362 (-5300 5375);
PAINT SKYBLUE (-5300 5375);
FORCEPROP 1 LAST VOLTAGE 25V
J 0
(-5300 5525);
DISPLAY 0.489362 (-5300 5525);
PAINT SKYBLUE (-5300 5525);
FORCEPROP 1 LAST PACK_TYPE 0402
J 0
(-5300 5325);
DISPLAY 0.489362 (-5300 5325);
PAINT SKYBLUE (-5300 5325);
FORCEPROP 2 LAST CDS_LIB pure_quanta
J 0
(-5350 5525);
DISPLAY INVISIBLE (-5350 5525);
FORCEPROP 1 LAST PATH I36
J 0
(-5300 5675);
DISPLAY 0.978723 (-5300 5675);
PAINT WHITE (-5300 5675);
DISPLAY INVISIBLE (-5300 5675);
FORCEADD Q_CAP..1
(-7600 5000);
FORCEPROP 1 LAST LOCATION PC567
J 0
(-7550 5100);
DISPLAY 0.489362 (-7550 5100);
PAINT SKYBLUE (-7550 5100);
FORCEPROP 0 LAST $SEC 1
J 0
(-7550 5150);
DISPLAY 0.680851 (-7550 5150);
PAINT MONO (-7550 5150);
DISPLAY INVISIBLE (-7550 5150);
FORCEPROP 0 LAST CDS_SEC 1
J 0
(-7550 5150);
DISPLAY 1.021277 (-7550 5150);
DISPLAY INVISIBLE (-7550 5150);
FORCEPROP 1 LASTPIN (-7600 5100) $PN 1
J 0
(-7590 5080);
DISPLAY 0.489362 (-7590 5080);
PAINT MONO (-7590 5080);
FORCEPROP 1 LASTPIN (-7600 4900) $PN 2
J 0
(-7590 4880);
DISPLAY 0.489362 (-7590 4880);
PAINT MONO (-7590 4880);
FORCEPROP 1 LAST MATERIAL X6S
J 0
(-7550 4900);
DISPLAY 0.489362 (-7550 4900);
PAINT SKYBLUE (-7550 4900);
FORCEPROP 1 LAST TOLERANCE 10%
J 0
(-7550 4950);
DISPLAY 0.489362 (-7550 4950);
PAINT SKYBLUE (-7550 4950);
FORCEPROP 1 LAST VALUE 2.2UF
J 0
(-7550 5050);
DISPLAY 0.489362 (-7550 5050);
PAINT SKYBLUE (-7550 5050);
FORCEPROP 1 LAST PART_NUMBER CH5222KEB01
J 0
(-7550 4850);
DISPLAY 0.489362 (-7550 4850);
PAINT SKYBLUE (-7550 4850);
FORCEPROP 1 LAST VOLTAGE 10V
J 0
(-7550 5000);
DISPLAY 0.489362 (-7550 5000);
PAINT SKYBLUE (-7550 5000);
FORCEPROP 1 LAST PACK_TYPE C0402
J 0
(-7550 4800);
DISPLAY 0.489362 (-7550 4800);
PAINT SKYBLUE (-7550 4800);
FORCEPROP 2 LAST CDS_LIB pure_quanta
J 0
(-7600 5000);
DISPLAY INVISIBLE (-7600 5000);
FORCEPROP 1 LAST PATH I37
J 0
(-7550 5150);
DISPLAY 0.978723 (-7550 5150);
PAINT WHITE (-7550 5150);
DISPLAY INVISIBLE (-7550 5150);
FORCEADD UNIVERSAL_GND..1
(-7600 4800);
FORCEPROP 3 LASTPIN (-7600 4850) SIG_NAME GND\g
J 0
(-7590 4860);
DISPLAY 0.659574 (-7590 4860);
PAINT MONO (-7590 4860);
DISPLAY INVISIBLE (-7590 4860);
FORCEPROP 2 LAST CDS_LIB pure_quanta_power
J 0
(-7600 4800);
DISPLAY INVISIBLE (-7600 4800);
FORCEPROP 1 LAST PATH I38
J 0
(-7525 4800);
DISPLAY 0.872340 (-7525 4800);
PAINT AQUA (-7525 4800);
DISPLAY INVISIBLE (-7525 4800);
FORCEPROP 1 LAST HDL_POWER GND
J 1
(-7575 4725);
DISPLAY 0.872340 (-7575 4725);
PAINT GREEN (-7575 4725);
DISPLAY INVISIBLE (-7575 4725);
FORCEADD UNIVERSAL_GND..1
(-7250 5250);
FORCEPROP 3 LASTPIN (-7250 5300) SIG_NAME GND\g
J 0
(-7240 5310);
DISPLAY 0.659574 (-7240 5310);
PAINT MONO (-7240 5310);
DISPLAY INVISIBLE (-7240 5310);
FORCEPROP 2 LAST CDS_LIB pure_quanta_power
J 0
(-7250 5250);
DISPLAY INVISIBLE (-7250 5250);
FORCEPROP 1 LAST PATH I39
J 0
(-7175 5250);
DISPLAY 0.872340 (-7175 5250);
PAINT AQUA (-7175 5250);
DISPLAY INVISIBLE (-7175 5250);
FORCEPROP 1 LAST HDL_POWER GND
J 1
(-7225 5175);
DISPLAY 0.872340 (-7225 5175);
PAINT GREEN (-7225 5175);
DISPLAY INVISIBLE (-7225 5175);
FORCEADD OFFPAGE..1
(-7200 4050);
FORCEPROP 2 LAST $XR0 169 
J 0
(-7452 4050);
DISPLAY 0.638298 (-7452 4050);
PAINT MONO (-7452 4050);
FORCEPROP 2 LAST CDS_LIB standard
J 2
(-7200 4050);
DISPLAY INVISIBLE (-7200 4050);
FORCEPROP 1 LAST OFFPAGE TRUE
J 0
(-6875 3925);
DISPLAY 0.872340 (-6875 3925);
PAINT GREEN (-6875 3925);
DISPLAY INVISIBLE (-6875 3925);
FORCEPROP 1 LAST COMMENT_BODY TRUE
J 0
(-7075 3950);
DISPLAY 0.872340 (-7075 3950);
PAINT GREEN (-7075 3950);
DISPLAY INVISIBLE (-7075 3950);
FORCEPROP 2 LAST PATH I4
J 0
(-7150 4125);
DISPLAY 1.021277 (-7150 4125);
DISPLAY INVISIBLE (-7150 4125);
FORCEADD Q_RES..2
(-7600 5500);
FORCEPROP 1 LAST LOCATION PR352
J 0
(-7555 5600);
DISPLAY 0.489362 (-7555 5600);
PAINT SKYBLUE (-7555 5600);
FORCEPROP 0 LAST $SEC 1
J 0
(-7550 5675);
DISPLAY 0.680851 (-7550 5675);
PAINT MONO (-7550 5675);
DISPLAY INVISIBLE (-7550 5675);
FORCEPROP 0 LAST CDS_SEC 1
J 0
(-7550 5675);
DISPLAY 1.021277 (-7550 5675);
DISPLAY INVISIBLE (-7550 5675);
FORCEPROP 1 LASTPIN (-7600 5600) $PN 1
J 0
(-7595 5562);
DISPLAY 0.489362 (-7595 5562);
PAINT MONO (-7595 5562);
FORCEPROP 1 LASTPIN (-7600 5400) $PN 2
J 0
(-7595 5410);
DISPLAY 0.489362 (-7595 5410);
PAINT MONO (-7595 5410);
FORCEPROP 1 LAST WATTAGE 1/16W
J 0
(-7550 5450);
DISPLAY 0.489362 (-7550 5450);
PAINT SKYBLUE (-7550 5450);
FORCEPROP 1 LAST MATERIAL CHIP
J 0
(-7550 5400);
DISPLAY 0.489362 (-7550 5400);
PAINT SKYBLUE (-7550 5400);
FORCEPROP 1 LAST TOLERANCE 1%
J 0
(-7550 5500);
DISPLAY 0.489362 (-7550 5500);
PAINT SKYBLUE (-7550 5500);
FORCEPROP 1 LAST VALUE 2.2
J 0
(-7550 5550);
DISPLAY 0.489362 (-7550 5550);
PAINT SKYBLUE (-7550 5550);
FORCEPROP 1 LAST PART_NUMBER CS-2202FB00
J 0
(-7550 5350);
DISPLAY 0.489362 (-7550 5350);
PAINT SKYBLUE (-7550 5350);
FORCEPROP 1 LAST PACK_TYPE 0402LF
J 0
(-7550 5300);
DISPLAY 0.489362 (-7550 5300);
PAINT SKYBLUE (-7550 5300);
FORCEPROP 2 LAST CDS_LIB pure_quanta
J 0
(-7600 5500);
DISPLAY INVISIBLE (-7600 5500);
FORCEPROP 1 LAST PATH I40
J 0
(-7550 5675);
DISPLAY 0.978723 (-7550 5675);
PAINT WHITE (-7550 5675);
DISPLAY INVISIBLE (-7550 5675);
FORCEADD Q_CAP..1
(-7250 5500);
FORCEPROP 1 LAST LOCATION PC568_C0P0_5
J 0
(-7200 5600);
DISPLAY 0.489362 (-7200 5600);
PAINT SKYBLUE (-7200 5600);
FORCEPROP 0 LAST $SEC 1
J 0
(-7200 5650);
DISPLAY 0.680851 (-7200 5650);
PAINT MONO (-7200 5650);
DISPLAY INVISIBLE (-7200 5650);
FORCEPROP 0 LAST CDS_SEC 1
J 0
(-7200 5650);
DISPLAY 1.021277 (-7200 5650);
DISPLAY INVISIBLE (-7200 5650);
FORCEPROP 1 LASTPIN (-7250 5600) $PN 1
J 0
(-7240 5580);
DISPLAY 0.489362 (-7240 5580);
PAINT MONO (-7240 5580);
FORCEPROP 1 LASTPIN (-7250 5400) $PN 2
J 0
(-7240 5380);
DISPLAY 0.489362 (-7240 5380);
PAINT MONO (-7240 5380);
FORCEPROP 1 LAST MATERIAL X6S
J 0
(-7200 5400);
DISPLAY 0.489362 (-7200 5400);
PAINT SKYBLUE (-7200 5400);
FORCEPROP 1 LAST TOLERANCE 10%
J 0
(-7200 5450);
DISPLAY 0.489362 (-7200 5450);
PAINT SKYBLUE (-7200 5450);
FORCEPROP 1 LAST VALUE 2.2UF
J 0
(-7200 5550);
DISPLAY 0.489362 (-7200 5550);
PAINT SKYBLUE (-7200 5550);
FORCEPROP 1 LAST PART_NUMBER CH5222KEB01
J 0
(-7200 5350);
DISPLAY 0.489362 (-7200 5350);
PAINT SKYBLUE (-7200 5350);
FORCEPROP 1 LAST VOLTAGE 10V
J 0
(-7200 5500);
DISPLAY 0.489362 (-7200 5500);
PAINT SKYBLUE (-7200 5500);
FORCEPROP 1 LAST PACK_TYPE C0402
J 0
(-7200 5300);
DISPLAY 0.489362 (-7200 5300);
PAINT SKYBLUE (-7200 5300);
FORCEPROP 2 LAST CDS_LIB pure_quanta
J 0
(-7250 5500);
DISPLAY INVISIBLE (-7250 5500);
FORCEPROP 1 LAST PATH I41
J 0
(-7200 5650);
DISPLAY 0.978723 (-7200 5650);
PAINT WHITE (-7200 5650);
DISPLAY INVISIBLE (-7200 5650);
FORCEADD ISL99390FRZTR5935..1
(-6100 4650);
FORCEPROP 1 LAST LOCATION PU48
J 0
(-6400 5525);
DISPLAY 0.489362 (-6400 5525);
PAINT SKYBLUE (-6400 5525);
FORCEPROP 0 LAST $SEC 1
J 0
(-6400 5675);
DISPLAY 0.680851 (-6400 5675);
PAINT MONO (-6400 5675);
DISPLAY INVISIBLE (-6400 5675);
FORCEPROP 0 LAST CDS_SEC 1
J 0
(-6400 5675);
DISPLAY 1.021277 (-6400 5675);
DISPLAY INVISIBLE (-6400 5675);
FORCEPROP 0 LASTPIN (-5700 4200) $PN 2
J 0
(-5690 4210);
DISPLAY 0.489362 (-5690 4210);
PAINT MONO (-5690 4210);
FORCEPROP 0 LASTPIN (-5700 5000) $PN 33
J 0
(-5690 5010);
DISPLAY 0.489362 (-5690 5010);
PAINT MONO (-5690 5010);
FORCEPROP 0 LASTPIN (-6550 4400) $PN 31
J 2
(-6560 4410);
DISPLAY 0.489362 (-6560 4410);
PAINT MONO (-6560 4410);
FORCEPROP 0 LASTPIN (-6550 4800) $PN 35
J 2
(-6560 4810);
DISPLAY 0.489362 (-6560 4810);
PAINT MONO (-6560 4810);
FORCEPROP 0 LASTPIN (-5700 4350) $PN 6
J 0
(-5690 4360);
DISPLAY 0.489362 (-5690 4360);
PAINT MONO (-5690 4360);
FORCEPROP 0 LASTPIN (-5700 4300) $PN 41
J 0
(-5690 4310);
DISPLAY 0.489362 (-5690 4310);
PAINT MONO (-5690 4310);
FORCEPROP 0 LASTPIN (-6550 4650) $PN 38
J 2
(-6560 4660);
DISPLAY 0.489362 (-6560 4660);
PAINT MONO (-6560 4660);
FORCEPROP 0 LASTPIN (-6550 4350) $PN 37
J 2
(-6560 4360);
DISPLAY 0.489362 (-6560 4360);
PAINT MONO (-6560 4360);
FORCEPROP 0 LASTPIN (-5700 4150) $PN 5
J 0
(-5690 4160);
DISPLAY 0.489362 (-5690 4160);
PAINT MONO (-5690 4160);
FORCEPROP 0 LASTPIN (-5700 4100) $PN 7_9-20_24
J 0
(-5690 4110);
DISPLAY 0.489362 (-5690 4110);
PAINT MONO (-5690 4110);
FORCEPROP 0 LASTPIN (-5700 4050) $PN 40
J 0
(-5690 4060);
DISPLAY 0.489362 (-5690 4060);
PAINT MONO (-5690 4060);
FORCEPROP 0 LASTPIN (-5700 4750) $PN 32
J 0
(-5690 4760);
DISPLAY 0.489362 (-5690 4760);
PAINT MONO (-5690 4760);
FORCEPROP 0 LASTPIN (-6550 5300) $PN 4
J 2
(-6560 5310);
DISPLAY 0.489362 (-6560 5310);
PAINT MONO (-6560 5310);
FORCEPROP 0 LASTPIN (-6550 4050) $PN 34
J 2
(-6560 4060);
DISPLAY 0.489362 (-6560 4060);
PAINT MONO (-6560 4060);
FORCEPROP 0 LASTPIN (-6550 4550) $PN 39
J 2
(-6560 4560);
DISPLAY 0.489362 (-6560 4560);
PAINT MONO (-6560 4560);
FORCEPROP 0 LASTPIN (-5700 4650) $PN 10_19
J 0
(-5690 4660);
DISPLAY 0.489362 (-5690 4660);
PAINT MONO (-5690 4660);
FORCEPROP 0 LASTPIN (-6550 4150) $PN 36
J 2
(-6560 4160);
DISPLAY 0.489362 (-6560 4160);
PAINT MONO (-6560 4160);
FORCEPROP 0 LASTPIN (-6550 5000) $PN 3
J 2
(-6560 5010);
DISPLAY 0.489362 (-6560 5010);
PAINT MONO (-6560 5010);
FORCEPROP 0 LASTPIN (-5700 5300) $PN 25_29
J 0
(-5690 5310);
DISPLAY 0.489362 (-5690 5310);
PAINT MONO (-5690 5310);
FORCEPROP 0 LASTPIN (-5700 5250) $PN 30
J 0
(-5690 5260);
DISPLAY 0.489362 (-5690 5260);
PAINT MONO (-5690 5260);
FORCEPROP 0 LASTPIN (-5700 4400) $PN 1
J 0
(-5690 4410);
DISPLAY 0.489362 (-5690 4410);
PAINT MONO (-5690 4410);
FORCEPROP 2 LAST PART_TYPE SMLF
J 0
(-6400 5625);
DISPLAY 1.021277 (-6400 5625);
FORCEPROP 1 LAST MATERIAL IC
J 0
(-6400 5375);
DISPLAY 0.489362 (-6400 5375);
PAINT SKYBLUE (-6400 5375);
FORCEPROP 2 LAST VALUE ISL99390FRZ-TR5935
J 0
(-6400 5575);
DISPLAY 0.489362 (-6400 5575);
PAINT SKYBLUE (-6400 5575);
FORCEPROP 1 LAST PART_NUMBER AL099390004
J 0
(-6400 5450);
DISPLAY 0.489362 (-6400 5450);
PAINT SKYBLUE (-6400 5450);
FORCEPROP 2 LAST CDS_LIB pure_quanta
J 0
(-6100 4650);
DISPLAY INVISIBLE (-6100 4650);
FORCEPROP 1 LAST NEEDS_NO_SIZE TRUE
J 0
(-6100 4650);
DISPLAY 0.723404 (-6100 4650);
PAINT GREEN (-6100 4650);
DISPLAY INVISIBLE (-6100 4650);
FORCEPROP 1 LAST CDS_LMAN_SYM_OUTLINE -300,700,250,-650
J 0
(-6100 4650);
DISPLAY 0.468085 (-6100 4650);
PAINT GREEN (-6100 4650);
DISPLAY INVISIBLE (-6100 4650);
FORCEPROP 1 LAST PATH I43
J 0
(-6100 4650);
DISPLAY 0.723404 (-6100 4650);
PAINT GREEN (-6100 4650);
DISPLAY INVISIBLE (-6100 4650);
FORCEADD ISL99390FRZTR5935..1
(-6100 1925);
FORCEPROP 1 LAST LOCATION PU10
J 0
(-6400 2800);
DISPLAY 0.489362 (-6400 2800);
PAINT SKYBLUE (-6400 2800);
FORCEPROP 0 LAST $SEC 1
J 0
(-6400 2950);
DISPLAY 0.680851 (-6400 2950);
PAINT MONO (-6400 2950);
DISPLAY INVISIBLE (-6400 2950);
FORCEPROP 0 LAST CDS_SEC 1
J 0
(-6400 2950);
DISPLAY 1.021277 (-6400 2950);
DISPLAY INVISIBLE (-6400 2950);
FORCEPROP 0 LASTPIN (-5700 1475) $PN 2
J 0
(-5690 1485);
DISPLAY 0.489362 (-5690 1485);
PAINT MONO (-5690 1485);
FORCEPROP 0 LASTPIN (-5700 2275) $PN 33
J 0
(-5690 2285);
DISPLAY 0.489362 (-5690 2285);
PAINT MONO (-5690 2285);
FORCEPROP 0 LASTPIN (-6550 1675) $PN 31
J 2
(-6560 1685);
DISPLAY 0.489362 (-6560 1685);
PAINT MONO (-6560 1685);
FORCEPROP 0 LASTPIN (-6550 2075) $PN 35
J 2
(-6560 2085);
DISPLAY 0.489362 (-6560 2085);
PAINT MONO (-6560 2085);
FORCEPROP 0 LASTPIN (-5700 1625) $PN 6
J 0
(-5690 1635);
DISPLAY 0.489362 (-5690 1635);
PAINT MONO (-5690 1635);
FORCEPROP 0 LASTPIN (-5700 1575) $PN 41
J 0
(-5690 1585);
DISPLAY 0.489362 (-5690 1585);
PAINT MONO (-5690 1585);
FORCEPROP 0 LASTPIN (-6550 1925) $PN 38
J 2
(-6560 1935);
DISPLAY 0.489362 (-6560 1935);
PAINT MONO (-6560 1935);
FORCEPROP 0 LASTPIN (-6550 1625) $PN 37
J 2
(-6560 1635);
DISPLAY 0.489362 (-6560 1635);
PAINT MONO (-6560 1635);
FORCEPROP 0 LASTPIN (-5700 1425) $PN 5
J 0
(-5690 1435);
DISPLAY 0.489362 (-5690 1435);
PAINT MONO (-5690 1435);
FORCEPROP 0 LASTPIN (-5700 1375) $PN 7_9-20_24
J 0
(-5690 1385);
DISPLAY 0.489362 (-5690 1385);
PAINT MONO (-5690 1385);
FORCEPROP 0 LASTPIN (-5700 1325) $PN 40
J 0
(-5690 1335);
DISPLAY 0.489362 (-5690 1335);
PAINT MONO (-5690 1335);
FORCEPROP 0 LASTPIN (-5700 2025) $PN 32
J 0
(-5690 2035);
DISPLAY 0.489362 (-5690 2035);
PAINT MONO (-5690 2035);
FORCEPROP 0 LASTPIN (-6550 2575) $PN 4
J 2
(-6560 2585);
DISPLAY 0.489362 (-6560 2585);
PAINT MONO (-6560 2585);
FORCEPROP 0 LASTPIN (-6550 1325) $PN 34
J 2
(-6560 1335);
DISPLAY 0.489362 (-6560 1335);
PAINT MONO (-6560 1335);
FORCEPROP 0 LASTPIN (-6550 1825) $PN 39
J 2
(-6560 1835);
DISPLAY 0.489362 (-6560 1835);
PAINT MONO (-6560 1835);
FORCEPROP 0 LASTPIN (-5700 1925) $PN 10_19
J 0
(-5690 1935);
DISPLAY 0.489362 (-5690 1935);
PAINT MONO (-5690 1935);
FORCEPROP 0 LASTPIN (-6550 1425) $PN 36
J 2
(-6560 1435);
DISPLAY 0.489362 (-6560 1435);
PAINT MONO (-6560 1435);
FORCEPROP 0 LASTPIN (-6550 2275) $PN 3
J 2
(-6560 2285);
DISPLAY 0.489362 (-6560 2285);
PAINT MONO (-6560 2285);
FORCEPROP 0 LASTPIN (-5700 2575) $PN 25_29
J 0
(-5690 2585);
DISPLAY 0.489362 (-5690 2585);
PAINT MONO (-5690 2585);
FORCEPROP 0 LASTPIN (-5700 2525) $PN 30
J 0
(-5690 2535);
DISPLAY 0.489362 (-5690 2535);
PAINT MONO (-5690 2535);
FORCEPROP 0 LASTPIN (-5700 1675) $PN 1
J 0
(-5690 1685);
DISPLAY 0.489362 (-5690 1685);
PAINT MONO (-5690 1685);
FORCEPROP 2 LAST PART_TYPE SMLF
J 0
(-6400 2900);
DISPLAY 1.021277 (-6400 2900);
FORCEPROP 1 LAST MATERIAL IC
J 0
(-6400 2650);
DISPLAY 0.489362 (-6400 2650);
PAINT SKYBLUE (-6400 2650);
FORCEPROP 2 LAST VALUE ISL99390FRZ-TR5935
J 0
(-6400 2850);
DISPLAY 0.489362 (-6400 2850);
PAINT SKYBLUE (-6400 2850);
FORCEPROP 1 LAST PART_NUMBER AL099390004
J 0
(-6400 2725);
DISPLAY 0.489362 (-6400 2725);
PAINT SKYBLUE (-6400 2725);
FORCEPROP 2 LAST CDS_LIB pure_quanta
J 0
(-6100 1925);
DISPLAY INVISIBLE (-6100 1925);
FORCEPROP 1 LAST NEEDS_NO_SIZE TRUE
J 0
(-6100 1925);
DISPLAY 0.723404 (-6100 1925);
PAINT GREEN (-6100 1925);
DISPLAY INVISIBLE (-6100 1925);
FORCEPROP 1 LAST CDS_LMAN_SYM_OUTLINE -300,700,250,-650
J 0
(-6100 1925);
DISPLAY 0.468085 (-6100 1925);
PAINT GREEN (-6100 1925);
DISPLAY INVISIBLE (-6100 1925);
FORCEPROP 1 LAST PATH I44
J 0
(-6100 1925);
DISPLAY 0.723404 (-6100 1925);
PAINT GREEN (-6100 1925);
DISPLAY INVISIBLE (-6100 1925);
FORCEADD VCC_CORE..1
(-1050 2075);
FORCEPROP 3 LASTPIN (-1050 2025) SIG_NAME PVDDCR_CPU0_P0\g
J 0
(-1040 2035);
DISPLAY 0.659574 (-1040 2035);
PAINT MONO (-1040 2035);
DISPLAY INVISIBLE (-1040 2035);
FORCEPROP 1 LAST HDL_POWER PVDDCR_CPU0_P0
J 1
(-1050 2125);
DISPLAY 0.489362 (-1050 2125);
PAINT GREEN (-1050 2125);
FORCEPROP 2 LAST CDS_LIB pure_quanta_power
J 0
(-1050 2075);
DISPLAY INVISIBLE (-1050 2075);
FORCEPROP 1 LAST PATH I45
J 0
(-1000 2100);
DISPLAY 0.872340 (-1000 2100);
PAINT AQUA (-1000 2100);
DISPLAY INVISIBLE (-1000 2100);
FORCEADD Q_CAP..1
(-1050 1750);
FORCEPROP 1 LAST LOCATION PC166_6
J 0
(-1000 1850);
DISPLAY 0.489362 (-1000 1850);
PAINT SKYBLUE (-1000 1850);
FORCEPROP 0 LAST $SEC 1
J 0
(-1000 1875);
DISPLAY 0.680851 (-1000 1875);
PAINT MONO (-1000 1875);
DISPLAY INVISIBLE (-1000 1875);
FORCEPROP 0 LAST CDS_SEC 1
J 0
(-1000 1875);
DISPLAY 1.021277 (-1000 1875);
DISPLAY INVISIBLE (-1000 1875);
FORCEPROP 1 LASTPIN (-1050 1850) $PN 1
J 0
(-1040 1830);
DISPLAY 0.489362 (-1040 1830);
PAINT MONO (-1040 1830);
FORCEPROP 1 LASTPIN (-1050 1650) $PN 2
J 0
(-1040 1630);
DISPLAY 0.489362 (-1040 1630);
PAINT MONO (-1040 1630);
FORCEPROP 1 LAST MATERIAL X6S
J 0
(-1000 1650);
DISPLAY 0.489362 (-1000 1650);
PAINT SKYBLUE (-1000 1650);
FORCEPROP 1 LAST TOLERANCE 20%
J 0
(-1000 1700);
DISPLAY 0.489362 (-1000 1700);
PAINT SKYBLUE (-1000 1700);
FORCEPROP 1 LAST VALUE 22UF
J 0
(-1000 1800);
DISPLAY 0.489362 (-1000 1800);
PAINT SKYBLUE (-1000 1800);
FORCEPROP 1 LAST PART_NUMBER TMP_QCH622KMEA01
J 0
(-1000 1600);
DISPLAY 0.489362 (-1000 1600);
PAINT SKYBLUE (-1000 1600);
FORCEPROP 1 LAST VOLTAGE 4V
J 0
(-1000 1750);
DISPLAY 0.489362 (-1000 1750);
PAINT SKYBLUE (-1000 1750);
FORCEPROP 1 LAST PACK_TYPE 0805
J 0
(-1000 1550);
DISPLAY 0.489362 (-1000 1550);
PAINT SKYBLUE (-1000 1550);
FORCEPROP 2 LAST CDS_LIB pure_quanta
J 0
(-1050 1750);
DISPLAY INVISIBLE (-1050 1750);
FORCEPROP 1 LAST PATH I46
J 0
(-1000 1900);
DISPLAY 0.978723 (-1000 1900);
PAINT WHITE (-1000 1900);
DISPLAY INVISIBLE (-1000 1900);
FORCEADD UNIVERSAL_GND..1
(-1050 1400);
FORCEPROP 3 LASTPIN (-1050 1450) SIG_NAME GND\g
J 0
(-1040 1460);
DISPLAY 0.659574 (-1040 1460);
PAINT MONO (-1040 1460);
DISPLAY INVISIBLE (-1040 1460);
FORCEPROP 2 LAST CDS_LIB pure_quanta_power
J 0
(-1050 1400);
DISPLAY INVISIBLE (-1050 1400);
FORCEPROP 1 LAST PATH I47
J 0
(-975 1400);
DISPLAY 0.872340 (-975 1400);
PAINT AQUA (-975 1400);
DISPLAY INVISIBLE (-975 1400);
FORCEPROP 1 LAST HDL_POWER GND
J 1
(-1025 1325);
DISPLAY 0.872340 (-1025 1325);
PAINT GREEN (-1025 1325);
DISPLAY INVISIBLE (-1025 1325);
FORCEADD Q_CAP..1
(-1475 1750);
FORCEPROP 1 LAST LOCATION PC163_6
J 0
(-1425 1850);
DISPLAY 0.489362 (-1425 1850);
PAINT SKYBLUE (-1425 1850);
FORCEPROP 0 LAST $SEC 1
J 0
(-1425 1875);
DISPLAY 0.680851 (-1425 1875);
PAINT MONO (-1425 1875);
DISPLAY INVISIBLE (-1425 1875);
FORCEPROP 0 LAST CDS_SEC 1
J 0
(-1425 1875);
DISPLAY 1.021277 (-1425 1875);
DISPLAY INVISIBLE (-1425 1875);
FORCEPROP 1 LASTPIN (-1475 1850) $PN 1
J 0
(-1465 1830);
DISPLAY 0.489362 (-1465 1830);
PAINT MONO (-1465 1830);
FORCEPROP 1 LASTPIN (-1475 1650) $PN 2
J 0
(-1465 1630);
DISPLAY 0.489362 (-1465 1630);
PAINT MONO (-1465 1630);
FORCEPROP 1 LAST MATERIAL X6S
J 0
(-1425 1650);
DISPLAY 0.489362 (-1425 1650);
PAINT SKYBLUE (-1425 1650);
FORCEPROP 1 LAST TOLERANCE 20%
J 0
(-1425 1700);
DISPLAY 0.489362 (-1425 1700);
PAINT SKYBLUE (-1425 1700);
FORCEPROP 1 LAST VALUE 22UF
J 0
(-1425 1800);
DISPLAY 0.489362 (-1425 1800);
PAINT SKYBLUE (-1425 1800);
FORCEPROP 1 LAST PART_NUMBER TMP_QCH622KMEA01
J 0
(-1425 1600);
DISPLAY 0.489362 (-1425 1600);
PAINT SKYBLUE (-1425 1600);
FORCEPROP 1 LAST VOLTAGE 4V
J 0
(-1425 1750);
DISPLAY 0.489362 (-1425 1750);
PAINT SKYBLUE (-1425 1750);
FORCEPROP 1 LAST PACK_TYPE 0805
J 0
(-1425 1550);
DISPLAY 0.489362 (-1425 1550);
PAINT SKYBLUE (-1425 1550);
FORCEPROP 2 LAST CDS_LIB pure_quanta
J 0
(-1475 1750);
DISPLAY INVISIBLE (-1475 1750);
FORCEPROP 1 LAST PATH I48
J 0
(-1425 1900);
DISPLAY 0.978723 (-1425 1900);
PAINT WHITE (-1425 1900);
DISPLAY INVISIBLE (-1425 1900);
FORCEADD OFFPAGE..3
(-1950 1675);
FORCEPROP 2 LAST $XR0 172 
J 0
(-1676 1675);
DISPLAY 0.638298 (-1676 1675);
PAINT MONO (-1676 1675);
FORCEPROP 2 LAST CDS_LIB standard
J 2
(-1950 1675);
DISPLAY INVISIBLE (-1950 1675);
FORCEPROP 1 LAST OFFPAGE TRUE
J 0
(-1625 1550);
DISPLAY 0.872340 (-1625 1550);
PAINT GREEN (-1625 1550);
DISPLAY INVISIBLE (-1625 1550);
FORCEPROP 1 LAST COMMENT_BODY TRUE
J 0
(-2000 1575);
DISPLAY 0.872340 (-2000 1575);
PAINT GREEN (-2000 1575);
DISPLAY INVISIBLE (-2000 1575);
FORCEPROP 2 LAST PATH I49
J 0
(-1675 1725);
DISPLAY 1.021277 (-1675 1725);
DISPLAY INVISIBLE (-1675 1725);
FORCEADD UNIVERSAL_GND..1
(-7600 4175);
FORCEPROP 3 LASTPIN (-7600 4225) SIG_NAME GND\g
J 0
(-7590 4235);
DISPLAY 0.659574 (-7590 4235);
PAINT MONO (-7590 4235);
DISPLAY INVISIBLE (-7590 4235);
FORCEPROP 2 LAST CDS_LIB pure_quanta_power
J 0
(-7600 4175);
DISPLAY INVISIBLE (-7600 4175);
FORCEPROP 1 LAST PATH I5
J 0
(-7525 4175);
DISPLAY 0.872340 (-7525 4175);
PAINT AQUA (-7525 4175);
DISPLAY INVISIBLE (-7525 4175);
FORCEPROP 1 LAST HDL_POWER GND
J 1
(-7575 4100);
DISPLAY 0.872340 (-7575 4100);
PAINT GREEN (-7575 4100);
DISPLAY INVISIBLE (-7575 4100);
FORCEADD VCC_CORE..1
(-4025 3100);
FORCEPROP 3 LASTPIN (-4025 3050) SIG_NAME SW_P12V_STBY_PVDDCR_CPU0_P0_FLT\g
J 0
(-4015 3060);
DISPLAY 0.659574 (-4015 3060);
PAINT MONO (-4015 3060);
DISPLAY INVISIBLE (-4015 3060);
FORCEPROP 1 LAST HDL_POWER SW_P12V_STBY_PVDDCR_CPU0_P0_FLT
J 1
(-4025 3150);
DISPLAY 0.489362 (-4025 3150);
PAINT GREEN (-4025 3150);
FORCEPROP 2 LAST CDS_LIB pure_quanta_power
J 0
(-4025 3100);
DISPLAY INVISIBLE (-4025 3100);
FORCEPROP 1 LAST PATH I50
J 0
(-3975 3125);
DISPLAY 0.872340 (-3975 3125);
PAINT AQUA (-3975 3125);
DISPLAY INVISIBLE (-3975 3125);
FORCEADD Q_CAP..1
(-4025 2800);
FORCEPROP 1 LAST LOCATION PC159_6
J 0
(-3975 2900);
DISPLAY 0.489362 (-3975 2900);
PAINT SKYBLUE (-3975 2900);
FORCEPROP 0 LAST $SEC 1
J 0
(-3975 2925);
DISPLAY 0.680851 (-3975 2925);
PAINT MONO (-3975 2925);
DISPLAY INVISIBLE (-3975 2925);
FORCEPROP 0 LAST CDS_SEC 1
J 0
(-3975 2925);
DISPLAY 1.021277 (-3975 2925);
DISPLAY INVISIBLE (-3975 2925);
FORCEPROP 1 LASTPIN (-4025 2900) $PN 1
J 0
(-4015 2880);
DISPLAY 0.489362 (-4015 2880);
PAINT MONO (-4015 2880);
FORCEPROP 1 LASTPIN (-4025 2700) $PN 2
J 0
(-4015 2680);
DISPLAY 0.489362 (-4015 2680);
PAINT MONO (-4015 2680);
FORCEPROP 1 LAST MATERIAL X6S
J 0
(-3975 2700);
DISPLAY 0.489362 (-3975 2700);
PAINT SKYBLUE (-3975 2700);
FORCEPROP 1 LAST TOLERANCE 10%
J 0
(-3975 2750);
DISPLAY 0.489362 (-3975 2750);
PAINT SKYBLUE (-3975 2750);
FORCEPROP 1 LAST VALUE 10UF
J 0
(-3975 2850);
DISPLAY 0.489362 (-3975 2850);
PAINT SKYBLUE (-3975 2850);
FORCEPROP 1 LAST PART_NUMBER CH6104KEA00
J 0
(-3975 2650);
DISPLAY 0.489362 (-3975 2650);
PAINT SKYBLUE (-3975 2650);
FORCEPROP 1 LAST VOLTAGE 25V
J 0
(-3975 2800);
DISPLAY 0.489362 (-3975 2800);
PAINT SKYBLUE (-3975 2800);
FORCEPROP 1 LAST PACK_TYPE C0805
J 0
(-3975 2600);
DISPLAY 0.489362 (-3975 2600);
PAINT SKYBLUE (-3975 2600);
FORCEPROP 2 LAST CDS_LIB pure_quanta
J 0
(-4025 2800);
DISPLAY INVISIBLE (-4025 2800);
FORCEPROP 1 LAST PATH I51
J 0
(-3975 2950);
DISPLAY 0.978723 (-3975 2950);
PAINT WHITE (-3975 2950);
DISPLAY INVISIBLE (-3975 2950);
FORCEADD UNIVERSAL_GND..1
(-4025 2450);
FORCEPROP 3 LASTPIN (-4025 2500) SIG_NAME GND\g
J 0
(-4015 2510);
DISPLAY 0.659574 (-4015 2510);
PAINT MONO (-4015 2510);
DISPLAY INVISIBLE (-4015 2510);
FORCEPROP 2 LAST CDS_LIB pure_quanta_power
J 0
(-4025 2450);
DISPLAY INVISIBLE (-4025 2450);
FORCEPROP 1 LAST PATH I52
J 0
(-3950 2450);
DISPLAY 0.872340 (-3950 2450);
PAINT AQUA (-3950 2450);
DISPLAY INVISIBLE (-3950 2450);
FORCEPROP 1 LAST HDL_POWER GND
J 1
(-4000 2375);
DISPLAY 0.872340 (-4000 2375);
PAINT GREEN (-4000 2375);
DISPLAY INVISIBLE (-4000 2375);
FORCEADD Q_INDUCTOR4P_14..1
(-2875 1800);
FORCEPROP 1 LAST LOCATION PL70
J 0
(-3100 2055);
DISPLAY 0.489362 (-3100 2055);
PAINT SKYBLUE (-3100 2055);
FORCEPROP 0 LAST $SEC 1
J 0
(-3100 2200);
DISPLAY 0.680851 (-3100 2200);
PAINT MONO (-3100 2200);
DISPLAY INVISIBLE (-3100 2200);
FORCEPROP 0 LAST CDS_SEC 1
J 0
(-3100 2200);
DISPLAY 1.021277 (-3100 2200);
DISPLAY INVISIBLE (-3100 2200);
FORCEPROP 0 LASTPIN (-3275 1925) $PN 1
J 2
(-3285 1935);
DISPLAY 0.489362 (-3285 1935);
PAINT MONO (-3285 1935);
FORCEPROP 0 LASTPIN (-3275 1675) $PN 2
J 2
(-3285 1685);
DISPLAY 0.489362 (-3285 1685);
PAINT MONO (-3285 1685);
FORCEPROP 0 LASTPIN (-2475 1675) $PN 3
J 0
(-2465 1685);
DISPLAY 0.489362 (-2465 1685);
PAINT MONO (-2465 1685);
FORCEPROP 0 LASTPIN (-2475 1925) $PN 4
J 0
(-2465 1935);
DISPLAY 0.489362 (-2465 1935);
PAINT MONO (-2465 1935);
FORCEPROP 2 LAST PART_TYPE SMLF
J 0
(-3100 2150);
DISPLAY 1.021277 (-3100 2150);
FORCEPROP 1 LAST MATERIAL IND
J 0
(-3100 2010);
DISPLAY 0.489362 (-3100 2010);
PAINT SKYBLUE (-3100 2010);
FORCEPROP 2 LAST VALUE 150NH
J 0
(-3100 2100);
DISPLAY 0.489362 (-3100 2100);
PAINT SKYBLUE (-3100 2100);
FORCEPROP 1 LAST PART_NUMBER CV+15^0TZ04
J 0
(-3100 1960);
DISPLAY 0.489362 (-3100 1960);
PAINT SKYBLUE (-3100 1960);
FORCEPROP 1 LAST NEEDS_NO_SIZE TRUE
J 0
(-2875 1800);
DISPLAY 0.468085 (-2875 1800);
PAINT GREEN (-2875 1800);
DISPLAY INVISIBLE (-2875 1800);
FORCEPROP 2 LAST CDS_LIB pure_quanta
J 0
(-2875 1800);
DISPLAY INVISIBLE (-2875 1800);
FORCEPROP 1 LAST PATH I53
J 0
(-2675 1955);
DISPLAY 0.723404 (-2675 1955);
PAINT GREEN (-2675 1955);
DISPLAY INVISIBLE (-2675 1955);
FORCEADD Q_CAP..1
(-3675 2150);
FORCEPROP 1 LAST LOCATION PC161
J 0
(-3625 2275);
DISPLAY 0.489362 (-3625 2275);
PAINT SKYBLUE (-3625 2275);
FORCEPROP 0 LAST $SEC 1
J 0
(-3625 2300);
DISPLAY 0.680851 (-3625 2300);
PAINT MONO (-3625 2300);
DISPLAY INVISIBLE (-3625 2300);
FORCEPROP 0 LAST CDS_SEC 1
J 0
(-3625 2300);
DISPLAY 1.021277 (-3625 2300);
DISPLAY INVISIBLE (-3625 2300);
FORCEPROP 1 LASTPIN (-3675 2250) $PN 1
J 0
(-3665 2230);
DISPLAY 0.489362 (-3665 2230);
PAINT MONO (-3665 2230);
FORCEPROP 1 LASTPIN (-3675 2050) $PN 2
J 0
(-3665 2030);
DISPLAY 0.489362 (-3665 2030);
PAINT MONO (-3665 2030);
FORCEPROP 1 LAST MATERIAL X7R
J 0
(-3625 2075);
DISPLAY 0.489362 (-3625 2075);
PAINT SKYBLUE (-3625 2075);
FORCEPROP 1 LAST TOLERANCE 10%
J 0
(-3625 2125);
DISPLAY 0.489362 (-3625 2125);
PAINT SKYBLUE (-3625 2125);
FORCEPROP 1 LAST VALUE 0.22UF
J 0
(-3625 2225);
DISPLAY 0.489362 (-3625 2225);
PAINT SKYBLUE (-3625 2225);
FORCEPROP 1 LAST PART_NUMBER CH4223K1B00
J 0
(-3625 2025);
DISPLAY 0.489362 (-3625 2025);
PAINT SKYBLUE (-3625 2025);
FORCEPROP 1 LAST VOLTAGE 16V
J 0
(-3625 2175);
DISPLAY 0.489362 (-3625 2175);
PAINT SKYBLUE (-3625 2175);
FORCEPROP 1 LAST PACK_TYPE 0402
J 0
(-3625 1975);
DISPLAY 0.489362 (-3625 1975);
PAINT SKYBLUE (-3625 1975);
FORCEPROP 2 LAST CDS_LIB pure_quanta
J 0
(-3675 2150);
DISPLAY INVISIBLE (-3675 2150);
FORCEPROP 1 LAST PATH I54
J 0
(-3625 2300);
DISPLAY 0.978723 (-3625 2300);
PAINT WHITE (-3625 2300);
DISPLAY INVISIBLE (-3625 2300);
FORCEADD Q_CAP..1
(-4325 2800);
FORCEPROP 1 LAST LOCATION PC158_6
J 0
(-4275 2900);
DISPLAY 0.489362 (-4275 2900);
PAINT SKYBLUE (-4275 2900);
FORCEPROP 0 LAST $SEC 1
J 0
(-4275 2925);
DISPLAY 0.680851 (-4275 2925);
PAINT MONO (-4275 2925);
DISPLAY INVISIBLE (-4275 2925);
FORCEPROP 0 LAST CDS_SEC 1
J 0
(-4275 2925);
DISPLAY 1.021277 (-4275 2925);
DISPLAY INVISIBLE (-4275 2925);
FORCEPROP 1 LASTPIN (-4325 2900) $PN 1
J 0
(-4315 2880);
DISPLAY 0.489362 (-4315 2880);
PAINT MONO (-4315 2880);
FORCEPROP 1 LASTPIN (-4325 2700) $PN 2
J 0
(-4315 2680);
DISPLAY 0.489362 (-4315 2680);
PAINT MONO (-4315 2680);
FORCEPROP 1 LAST MATERIAL X6S
J 0
(-4275 2700);
DISPLAY 0.489362 (-4275 2700);
PAINT SKYBLUE (-4275 2700);
FORCEPROP 1 LAST TOLERANCE 10%
J 0
(-4275 2750);
DISPLAY 0.489362 (-4275 2750);
PAINT SKYBLUE (-4275 2750);
FORCEPROP 1 LAST VALUE 10UF
J 0
(-4275 2850);
DISPLAY 0.489362 (-4275 2850);
PAINT SKYBLUE (-4275 2850);
FORCEPROP 1 LAST PART_NUMBER CH6104KEA00
J 0
(-4275 2650);
DISPLAY 0.489362 (-4275 2650);
PAINT SKYBLUE (-4275 2650);
FORCEPROP 1 LAST VOLTAGE 25V
J 0
(-4275 2800);
DISPLAY 0.489362 (-4275 2800);
PAINT SKYBLUE (-4275 2800);
FORCEPROP 1 LAST PACK_TYPE C0805
J 0
(-4275 2600);
DISPLAY 0.489362 (-4275 2600);
PAINT SKYBLUE (-4275 2600);
FORCEPROP 2 LAST CDS_LIB pure_quanta
J 0
(-4325 2800);
DISPLAY INVISIBLE (-4325 2800);
FORCEPROP 1 LAST PATH I56
J 0
(-4275 2950);
DISPLAY 0.978723 (-4275 2950);
PAINT WHITE (-4275 2950);
DISPLAY INVISIBLE (-4275 2950);
FORCEADD Q_CAP..1
(-4650 2800);
FORCEPROP 1 LAST LOCATION PC157_6
J 0
(-4600 2900);
DISPLAY 0.489362 (-4600 2900);
PAINT SKYBLUE (-4600 2900);
FORCEPROP 0 LAST $SEC 1
J 0
(-4600 2925);
DISPLAY 0.680851 (-4600 2925);
PAINT MONO (-4600 2925);
DISPLAY INVISIBLE (-4600 2925);
FORCEPROP 0 LAST CDS_SEC 1
J 0
(-4600 2925);
DISPLAY 1.021277 (-4600 2925);
DISPLAY INVISIBLE (-4600 2925);
FORCEPROP 1 LASTPIN (-4650 2900) $PN 1
J 0
(-4640 2880);
DISPLAY 0.489362 (-4640 2880);
PAINT MONO (-4640 2880);
FORCEPROP 1 LASTPIN (-4650 2700) $PN 2
J 0
(-4640 2680);
DISPLAY 0.489362 (-4640 2680);
PAINT MONO (-4640 2680);
FORCEPROP 1 LAST MATERIAL X6S
J 0
(-4600 2700);
DISPLAY 0.489362 (-4600 2700);
PAINT SKYBLUE (-4600 2700);
FORCEPROP 1 LAST TOLERANCE 10%
J 0
(-4600 2750);
DISPLAY 0.489362 (-4600 2750);
PAINT SKYBLUE (-4600 2750);
FORCEPROP 1 LAST VALUE 10UF
J 0
(-4600 2850);
DISPLAY 0.489362 (-4600 2850);
PAINT SKYBLUE (-4600 2850);
FORCEPROP 1 LAST PART_NUMBER CH6104KEA00
J 0
(-4600 2650);
DISPLAY 0.489362 (-4600 2650);
PAINT SKYBLUE (-4600 2650);
FORCEPROP 1 LAST VOLTAGE 25V
J 0
(-4600 2800);
DISPLAY 0.489362 (-4600 2800);
PAINT SKYBLUE (-4600 2800);
FORCEPROP 1 LAST PACK_TYPE C0805
J 0
(-4600 2600);
DISPLAY 0.489362 (-4600 2600);
PAINT SKYBLUE (-4600 2600);
FORCEPROP 2 LAST CDS_LIB pure_quanta
J 0
(-4650 2800);
DISPLAY INVISIBLE (-4650 2800);
FORCEPROP 1 LAST PATH I57
J 0
(-4600 2950);
DISPLAY 0.978723 (-4600 2950);
PAINT WHITE (-4600 2950);
DISPLAY INVISIBLE (-4600 2950);
FORCEADD Q_CAP..1
(-4975 2800);
FORCEPROP 1 LAST LOCATION PC154_6
J 0
(-4925 2900);
DISPLAY 0.489362 (-4925 2900);
PAINT SKYBLUE (-4925 2900);
FORCEPROP 0 LAST $SEC 1
J 0
(-4925 2925);
DISPLAY 0.680851 (-4925 2925);
PAINT MONO (-4925 2925);
DISPLAY INVISIBLE (-4925 2925);
FORCEPROP 0 LAST CDS_SEC 1
J 0
(-4925 2925);
DISPLAY 1.021277 (-4925 2925);
DISPLAY INVISIBLE (-4925 2925);
FORCEPROP 1 LASTPIN (-4975 2900) $PN 1
J 0
(-4965 2880);
DISPLAY 0.489362 (-4965 2880);
PAINT MONO (-4965 2880);
FORCEPROP 1 LASTPIN (-4975 2700) $PN 2
J 0
(-4965 2680);
DISPLAY 0.489362 (-4965 2680);
PAINT MONO (-4965 2680);
FORCEPROP 1 LAST MATERIAL X6S
J 0
(-4925 2700);
DISPLAY 0.489362 (-4925 2700);
PAINT SKYBLUE (-4925 2700);
FORCEPROP 1 LAST TOLERANCE 10%
J 0
(-4925 2750);
DISPLAY 0.489362 (-4925 2750);
PAINT SKYBLUE (-4925 2750);
FORCEPROP 1 LAST VALUE 1UF
J 0
(-4925 2850);
DISPLAY 0.489362 (-4925 2850);
PAINT SKYBLUE (-4925 2850);
FORCEPROP 1 LAST PART_NUMBER CH5104KEB02
J 0
(-4925 2650);
DISPLAY 0.489362 (-4925 2650);
PAINT SKYBLUE (-4925 2650);
FORCEPROP 1 LAST VOLTAGE 25V
J 0
(-4925 2800);
DISPLAY 0.489362 (-4925 2800);
PAINT SKYBLUE (-4925 2800);
FORCEPROP 1 LAST PACK_TYPE C0402
J 0
(-4925 2600);
DISPLAY 0.489362 (-4925 2600);
PAINT SKYBLUE (-4925 2600);
FORCEPROP 2 LAST CDS_LIB pure_quanta
J 0
(-4975 2800);
DISPLAY INVISIBLE (-4975 2800);
FORCEPROP 1 LAST PATH I58
J 0
(-4925 2950);
DISPLAY 0.978723 (-4925 2950);
PAINT WHITE (-4925 2950);
DISPLAY INVISIBLE (-4925 2950);
FORCEADD Q_RES..1
(-4300 875);
FORCEPROP 1 LAST LOCATION PR433
J 0
(-4325 925);
DISPLAY 0.489362 (-4325 925);
PAINT SKYBLUE (-4325 925);
FORCEPROP 0 LAST $SEC 1
J 0
(-4300 950);
DISPLAY 0.680851 (-4300 950);
PAINT MONO (-4300 950);
DISPLAY INVISIBLE (-4300 950);
FORCEPROP 0 LAST CDS_SEC 1
J 0
(-4300 950);
DISPLAY 1.021277 (-4300 950);
DISPLAY INVISIBLE (-4300 950);
FORCEPROP 1 LASTPIN (-4400 875) $PN 1
J 0
(-4388 887);
DISPLAY 0.489362 (-4388 887);
PAINT MONO (-4388 887);
FORCEPROP 1 LASTPIN (-4200 875) $PN 2
J 0
(-4238 887);
DISPLAY 0.489362 (-4238 887);
PAINT MONO (-4238 887);
FORCEPROP 1 LAST WATTAGE 1/16W
J 0
(-4200 825);
DISPLAY 0.489362 (-4200 825);
PAINT SKYBLUE (-4200 825);
FORCEPROP 1 LAST MATERIAL CHIP
J 0
(-4550 775);
DISPLAY 0.489362 (-4550 775);
PAINT SKYBLUE (-4550 775);
FORCEPROP 1 LAST TOLERANCE 5%
J 0
(-4175 900);
DISPLAY 0.489362 (-4175 900);
PAINT SKYBLUE (-4175 900);
FORCEPROP 1 LAST VALUE 0
J 2
(-4425 900);
DISPLAY 0.489362 (-4425 900);
PAINT SKYBLUE (-4425 900);
FORCEPROP 1 LAST PART_NUMBER CS00002JB38
J 0
(-4550 825);
DISPLAY 0.489362 (-4550 825);
PAINT SKYBLUE (-4550 825);
FORCEPROP 1 LAST PACK_TYPE 0402LF
J 0
(-4200 775);
DISPLAY 0.489362 (-4200 775);
PAINT SKYBLUE (-4200 775);
FORCEPROP 2 LAST CDS_LIB pure_quanta
J 0
(-4300 875);
DISPLAY INVISIBLE (-4300 875);
FORCEPROP 1 LAST PATH I59
J 0
(-4350 1025);
DISPLAY 0.978723 (-4350 1025);
PAINT WHITE (-4350 1025);
DISPLAY INVISIBLE (-4350 1025);
FORCEADD OFFPAGE..2
R 2
(-7225 4150);
FORCEPROP 2 LAST $XR3 169 
J 0
(-7720 4114);
DISPLAY 0.638298 (-7720 4114);
PAINT MONO (-7720 4114);
FORCEPROP 2 LAST $XR2 172 
J 0
(-7600 4114);
DISPLAY 0.638298 (-7600 4114);
PAINT MONO (-7600 4114);
FORCEPROP 2 LAST $XR1 171 
J 0
(-7480 4114);
DISPLAY 0.638298 (-7480 4114);
PAINT MONO (-7480 4114);
FORCEPROP 2 LAST $XR0 170 
J 0
(-7480 4150);
DISPLAY 0.638298 (-7480 4150);
PAINT MONO (-7480 4150);
FORCEPROP 2 LAST CDS_LIB standard
J 0
(-7225 4150);
DISPLAY INVISIBLE (-7225 4150);
FORCEPROP 1 LAST OFFPAGE TRUE
J 2
(-7550 4025);
DISPLAY 0.872340 (-7550 4025);
PAINT GREEN (-7550 4025);
DISPLAY INVISIBLE (-7550 4025);
FORCEPROP 1 LAST COMMENT_BODY TRUE
J 2
(-7180 4055);
DISPLAY 0.872340 (-7180 4055);
PAINT GREEN (-7180 4055);
DISPLAY INVISIBLE (-7180 4055);
FORCEPROP 2 LAST PATH I6
J 0
(-7175 4225);
DISPLAY 1.021277 (-7175 4225);
DISPLAY INVISIBLE (-7175 4225);
FORCEADD Q_RES..1
(-4675 2275);
FORCEPROP 1 LAST LOCATION PR432
J 0
(-4700 2325);
DISPLAY 0.489362 (-4700 2325);
PAINT SKYBLUE (-4700 2325);
FORCEPROP 0 LAST $SEC 1
J 0
(-4650 2350);
DISPLAY 0.680851 (-4650 2350);
PAINT MONO (-4650 2350);
DISPLAY INVISIBLE (-4650 2350);
FORCEPROP 0 LAST CDS_SEC 1
J 0
(-4650 2350);
DISPLAY 1.021277 (-4650 2350);
DISPLAY INVISIBLE (-4650 2350);
FORCEPROP 1 LASTPIN (-4775 2275) $PN 1
J 0
(-4763 2287);
DISPLAY 0.489362 (-4763 2287);
PAINT MONO (-4763 2287);
FORCEPROP 1 LASTPIN (-4575 2275) $PN 2
J 0
(-4613 2287);
DISPLAY 0.489362 (-4613 2287);
PAINT MONO (-4613 2287);
FORCEPROP 1 LAST TOLERANCE 1%
J 0
(-4575 2300);
DISPLAY 0.489362 (-4575 2300);
PAINT SKYBLUE (-4575 2300);
FORCEPROP 1 LAST MATERIAL CHIP
J 0
(-4925 2175);
DISPLAY 0.489362 (-4925 2175);
PAINT SKYBLUE (-4925 2175);
FORCEPROP 1 LAST WATTAGE 1/16W
J 0
(-4575 2225);
DISPLAY 0.489362 (-4575 2225);
PAINT SKYBLUE (-4575 2225);
FORCEPROP 1 LAST PACK_TYPE 0402LF
J 0
(-4575 2175);
DISPLAY 0.489362 (-4575 2175);
PAINT SKYBLUE (-4575 2175);
FORCEPROP 1 LAST VALUE 4.7
J 2
(-4775 2300);
DISPLAY 0.489362 (-4775 2300);
PAINT SKYBLUE (-4775 2300);
FORCEPROP 1 LAST PART_NUMBER CS-4702FB19
J 0
(-4925 2225);
DISPLAY 0.489362 (-4925 2225);
PAINT SKYBLUE (-4925 2225);
FORCEPROP 1 LAST PATH I60
J 0
(-4725 2425);
DISPLAY 0.978723 (-4725 2425);
PAINT WHITE (-4725 2425);
DISPLAY INVISIBLE (-4725 2425);
FORCEPROP 2 LAST CDS_LIB pure_quanta
J 0
(-4675 2275);
DISPLAY INVISIBLE (-4675 2275);
FORCEADD Q_CAP..1
(-5350 2800);
FORCEPROP 1 LAST LOCATION PC153_6
J 0
(-5300 2900);
DISPLAY 0.489362 (-5300 2900);
PAINT SKYBLUE (-5300 2900);
FORCEPROP 0 LAST $SEC 1
J 0
(-5300 2950);
DISPLAY 0.680851 (-5300 2950);
PAINT MONO (-5300 2950);
DISPLAY INVISIBLE (-5300 2950);
FORCEPROP 0 LAST CDS_SEC 1
J 0
(-5300 2950);
DISPLAY 1.021277 (-5300 2950);
DISPLAY INVISIBLE (-5300 2950);
FORCEPROP 1 LASTPIN (-5350 2900) $PN 1
J 0
(-5340 2880);
DISPLAY 0.489362 (-5340 2880);
PAINT MONO (-5340 2880);
FORCEPROP 1 LASTPIN (-5350 2700) $PN 2
J 0
(-5340 2680);
DISPLAY 0.489362 (-5340 2680);
PAINT MONO (-5340 2680);
FORCEPROP 1 LAST MATERIAL X7R
J 0
(-5300 2700);
DISPLAY 0.489362 (-5300 2700);
PAINT SKYBLUE (-5300 2700);
FORCEPROP 1 LAST TOLERANCE 10%
J 0
(-5300 2750);
DISPLAY 0.489362 (-5300 2750);
PAINT SKYBLUE (-5300 2750);
FORCEPROP 1 LAST VALUE 0.1UF
J 0
(-5300 2850);
DISPLAY 0.489362 (-5300 2850);
PAINT SKYBLUE (-5300 2850);
FORCEPROP 1 LAST PART_NUMBER CH4104K1B00
J 0
(-5300 2650);
DISPLAY 0.489362 (-5300 2650);
PAINT SKYBLUE (-5300 2650);
FORCEPROP 1 LAST VOLTAGE 25V
J 0
(-5300 2800);
DISPLAY 0.489362 (-5300 2800);
PAINT SKYBLUE (-5300 2800);
FORCEPROP 1 LAST PACK_TYPE 0402
J 0
(-5300 2600);
DISPLAY 0.489362 (-5300 2600);
PAINT SKYBLUE (-5300 2600);
FORCEPROP 2 LAST CDS_LIB pure_quanta
J 0
(-5350 2800);
DISPLAY INVISIBLE (-5350 2800);
FORCEPROP 1 LAST PATH I61
J 0
(-5300 2950);
DISPLAY 0.978723 (-5300 2950);
PAINT WHITE (-5300 2950);
DISPLAY INVISIBLE (-5300 2950);
FORCEADD Q_CAP..1
(-7250 2800);
FORCEPROP 1 LAST LOCATION PC152_C0P0_6
J 0
(-7200 2900);
DISPLAY 0.489362 (-7200 2900);
PAINT SKYBLUE (-7200 2900);
FORCEPROP 0 LAST $SEC 1
J 0
(-7200 2950);
DISPLAY 0.680851 (-7200 2950);
PAINT MONO (-7200 2950);
DISPLAY INVISIBLE (-7200 2950);
FORCEPROP 0 LAST CDS_SEC 1
J 0
(-7200 2950);
DISPLAY 1.021277 (-7200 2950);
DISPLAY INVISIBLE (-7200 2950);
FORCEPROP 1 LASTPIN (-7250 2900) $PN 1
J 0
(-7240 2880);
DISPLAY 0.489362 (-7240 2880);
PAINT MONO (-7240 2880);
FORCEPROP 1 LASTPIN (-7250 2700) $PN 2
J 0
(-7240 2680);
DISPLAY 0.489362 (-7240 2680);
PAINT MONO (-7240 2680);
FORCEPROP 1 LAST MATERIAL X6S
J 0
(-7200 2700);
DISPLAY 0.489362 (-7200 2700);
PAINT SKYBLUE (-7200 2700);
FORCEPROP 1 LAST TOLERANCE 10%
J 0
(-7200 2750);
DISPLAY 0.489362 (-7200 2750);
PAINT SKYBLUE (-7200 2750);
FORCEPROP 1 LAST VALUE 2.2UF
J 0
(-7200 2850);
DISPLAY 0.489362 (-7200 2850);
PAINT SKYBLUE (-7200 2850);
FORCEPROP 1 LAST PART_NUMBER CH5222KEB01
J 0
(-7200 2650);
DISPLAY 0.489362 (-7200 2650);
PAINT SKYBLUE (-7200 2650);
FORCEPROP 1 LAST VOLTAGE 10V
J 0
(-7200 2800);
DISPLAY 0.489362 (-7200 2800);
PAINT SKYBLUE (-7200 2800);
FORCEPROP 1 LAST PACK_TYPE C0402
J 0
(-7200 2600);
DISPLAY 0.489362 (-7200 2600);
PAINT SKYBLUE (-7200 2600);
FORCEPROP 2 LAST CDS_LIB pure_quanta
J 0
(-7250 2800);
DISPLAY INVISIBLE (-7250 2800);
FORCEPROP 1 LAST PATH I63
J 0
(-7200 2950);
DISPLAY 0.978723 (-7200 2950);
PAINT WHITE (-7200 2950);
DISPLAY INVISIBLE (-7200 2950);
FORCEADD UNIVERSAL_GND..1
(-7250 2525);
FORCEPROP 3 LASTPIN (-7250 2575) SIG_NAME GND\g
J 0
(-7240 2585);
DISPLAY 0.659574 (-7240 2585);
PAINT MONO (-7240 2585);
DISPLAY INVISIBLE (-7240 2585);
FORCEPROP 2 LAST CDS_LIB pure_quanta_power
J 0
(-7250 2525);
DISPLAY INVISIBLE (-7250 2525);
FORCEPROP 1 LAST PATH I64
J 0
(-7175 2525);
DISPLAY 0.872340 (-7175 2525);
PAINT AQUA (-7175 2525);
DISPLAY INVISIBLE (-7175 2525);
FORCEPROP 1 LAST HDL_POWER GND
J 1
(-7225 2450);
DISPLAY 0.872340 (-7225 2450);
PAINT GREEN (-7225 2450);
DISPLAY INVISIBLE (-7225 2450);
FORCEADD Q_RES..2
(-7600 2775);
FORCEPROP 1 LAST LOCATION PR430
J 0
(-7555 2900);
DISPLAY 0.489362 (-7555 2900);
PAINT SKYBLUE (-7555 2900);
FORCEPROP 0 LAST $SEC 1
J 0
(-7550 2950);
DISPLAY 0.680851 (-7550 2950);
PAINT MONO (-7550 2950);
DISPLAY INVISIBLE (-7550 2950);
FORCEPROP 0 LAST CDS_SEC 1
J 0
(-7550 2950);
DISPLAY 1.021277 (-7550 2950);
DISPLAY INVISIBLE (-7550 2950);
FORCEPROP 1 LASTPIN (-7600 2875) $PN 1
J 0
(-7595 2837);
DISPLAY 0.489362 (-7595 2837);
PAINT MONO (-7595 2837);
FORCEPROP 1 LASTPIN (-7600 2675) $PN 2
J 0
(-7595 2685);
DISPLAY 0.489362 (-7595 2685);
PAINT MONO (-7595 2685);
FORCEPROP 1 LAST WATTAGE 1/16W
J 0
(-7550 2750);
DISPLAY 0.489362 (-7550 2750);
PAINT SKYBLUE (-7550 2750);
FORCEPROP 1 LAST MATERIAL CHIP
J 0
(-7550 2700);
DISPLAY 0.489362 (-7550 2700);
PAINT SKYBLUE (-7550 2700);
FORCEPROP 1 LAST TOLERANCE 1%
J 0
(-7550 2800);
DISPLAY 0.489362 (-7550 2800);
PAINT SKYBLUE (-7550 2800);
FORCEPROP 1 LAST VALUE 2.2
J 0
(-7550 2850);
DISPLAY 0.489362 (-7550 2850);
PAINT SKYBLUE (-7550 2850);
FORCEPROP 1 LAST PART_NUMBER CS-2202FB00
J 0
(-7550 2650);
DISPLAY 0.489362 (-7550 2650);
PAINT SKYBLUE (-7550 2650);
FORCEPROP 1 LAST PACK_TYPE 0402LF
J 0
(-7550 2600);
DISPLAY 0.489362 (-7550 2600);
PAINT SKYBLUE (-7550 2600);
FORCEPROP 2 LAST CDS_LIB pure_quanta
J 0
(-7600 2775);
DISPLAY INVISIBLE (-7600 2775);
FORCEPROP 1 LAST PATH I65
J 0
(-7550 2950);
DISPLAY 0.978723 (-7550 2950);
PAINT WHITE (-7550 2950);
DISPLAY INVISIBLE (-7550 2950);
FORCEADD OFFPAGE..2
R 2
(-7250 1925);
FORCEPROP 2 LAST $XR0 169 
J 0
(-7505 1925);
DISPLAY 0.638298 (-7505 1925);
PAINT MONO (-7505 1925);
FORCEPROP 2 LAST CDS_LIB standard
J 2
(-7250 1925);
DISPLAY INVISIBLE (-7250 1925);
FORCEPROP 1 LAST OFFPAGE TRUE
J 2
(-7575 1800);
DISPLAY 0.872340 (-7575 1800);
PAINT GREEN (-7575 1800);
DISPLAY INVISIBLE (-7575 1800);
FORCEPROP 1 LAST COMMENT_BODY TRUE
J 2
(-7205 1830);
DISPLAY 0.872340 (-7205 1830);
PAINT GREEN (-7205 1830);
DISPLAY INVISIBLE (-7205 1830);
FORCEPROP 2 LAST PATH I66
J 0
(-7500 1975);
DISPLAY 1.021277 (-7500 1975);
DISPLAY INVISIBLE (-7500 1975);
FORCEADD Q_CAP..1
(-7600 2275);
FORCEPROP 1 LAST LOCATION PC151
J 0
(-7550 2375);
DISPLAY 0.489362 (-7550 2375);
PAINT SKYBLUE (-7550 2375);
FORCEPROP 0 LAST $SEC 1
J 0
(-7550 2425);
DISPLAY 0.680851 (-7550 2425);
PAINT MONO (-7550 2425);
DISPLAY INVISIBLE (-7550 2425);
FORCEPROP 0 LAST CDS_SEC 1
J 0
(-7550 2425);
DISPLAY 1.021277 (-7550 2425);
DISPLAY INVISIBLE (-7550 2425);
FORCEPROP 1 LASTPIN (-7600 2375) $PN 1
J 0
(-7590 2355);
DISPLAY 0.489362 (-7590 2355);
PAINT MONO (-7590 2355);
FORCEPROP 1 LASTPIN (-7600 2175) $PN 2
J 0
(-7590 2155);
DISPLAY 0.489362 (-7590 2155);
PAINT MONO (-7590 2155);
FORCEPROP 1 LAST MATERIAL X6S
J 0
(-7550 2175);
DISPLAY 0.489362 (-7550 2175);
PAINT SKYBLUE (-7550 2175);
FORCEPROP 1 LAST TOLERANCE 10%
J 0
(-7550 2225);
DISPLAY 0.489362 (-7550 2225);
PAINT SKYBLUE (-7550 2225);
FORCEPROP 1 LAST VALUE 2.2UF
J 0
(-7550 2325);
DISPLAY 0.489362 (-7550 2325);
PAINT SKYBLUE (-7550 2325);
FORCEPROP 1 LAST PART_NUMBER CH5222KEB01
J 0
(-7550 2125);
DISPLAY 0.489362 (-7550 2125);
PAINT SKYBLUE (-7550 2125);
FORCEPROP 1 LAST VOLTAGE 10V
J 0
(-7550 2275);
DISPLAY 0.489362 (-7550 2275);
PAINT SKYBLUE (-7550 2275);
FORCEPROP 1 LAST PACK_TYPE C0402
J 0
(-7550 2075);
DISPLAY 0.489362 (-7550 2075);
PAINT SKYBLUE (-7550 2075);
FORCEPROP 2 LAST CDS_LIB pure_quanta
J 0
(-7600 2275);
DISPLAY INVISIBLE (-7600 2275);
FORCEPROP 1 LAST PATH I67
J 0
(-7550 2425);
DISPLAY 0.978723 (-7550 2425);
PAINT WHITE (-7550 2425);
DISPLAY INVISIBLE (-7550 2425);
FORCEADD UNIVERSAL_GND..1
(-7600 2075);
FORCEPROP 3 LASTPIN (-7600 2125) SIG_NAME GND\g
J 0
(-7590 2135);
DISPLAY 0.659574 (-7590 2135);
PAINT MONO (-7590 2135);
DISPLAY INVISIBLE (-7590 2135);
FORCEPROP 2 LAST CDS_LIB pure_quanta_power
J 0
(-7600 2075);
DISPLAY INVISIBLE (-7600 2075);
FORCEPROP 1 LAST PATH I68
J 0
(-7525 2075);
DISPLAY 0.872340 (-7525 2075);
PAINT AQUA (-7525 2075);
DISPLAY INVISIBLE (-7525 2075);
FORCEPROP 1 LAST HDL_POWER GND
J 1
(-7575 2000);
DISPLAY 0.872340 (-7575 2000);
PAINT GREEN (-7575 2000);
DISPLAY INVISIBLE (-7575 2000);
FORCEADD Q_RES..1
(-7275 1625);
FORCEPROP 1 LAST LOCATION PR431
J 0
(-7300 1675);
DISPLAY 0.489362 (-7300 1675);
PAINT SKYBLUE (-7300 1675);
FORCEPROP 0 LAST $SEC 1
J 0
(-7275 1700);
DISPLAY 0.680851 (-7275 1700);
PAINT MONO (-7275 1700);
DISPLAY INVISIBLE (-7275 1700);
FORCEPROP 0 LAST CDS_SEC 1
J 0
(-7275 1700);
DISPLAY 1.021277 (-7275 1700);
DISPLAY INVISIBLE (-7275 1700);
FORCEPROP 1 LASTPIN (-7375 1625) $PN 1
J 0
(-7363 1637);
DISPLAY 0.489362 (-7363 1637);
PAINT MONO (-7363 1637);
FORCEPROP 1 LASTPIN (-7175 1625) $PN 2
J 0
(-7213 1637);
DISPLAY 0.489362 (-7213 1637);
PAINT MONO (-7213 1637);
FORCEPROP 1 LAST WATTAGE 1/16W
J 0
(-7175 1525);
DISPLAY 0.489362 (-7175 1525);
PAINT SKYBLUE (-7175 1525);
FORCEPROP 1 LAST MATERIAL EMPTY
J 0
(-7575 1525);
DISPLAY 0.489362 (-7575 1525);
PAINT RED (-7575 1525);
FORCEPROP 1 LAST TOLERANCE 1%
J 0
(-7150 1650);
DISPLAY 0.489362 (-7150 1650);
PAINT SKYBLUE (-7150 1650);
FORCEPROP 1 LAST VALUE 8.87K
J 2
(-7400 1650);
DISPLAY 0.489362 (-7400 1650);
PAINT SKYBLUE (-7400 1650);
FORCEPROP 1 LAST PART_NUMBER CS28872FB01
J 0
(-7575 1575);
DISPLAY 0.489362 (-7575 1575);
PAINT SKYBLUE (-7575 1575);
FORCEPROP 1 LAST PACK_TYPE 0402LF
J 0
(-7175 1575);
DISPLAY 0.489362 (-7175 1575);
PAINT SKYBLUE (-7175 1575);
FORCEPROP 2 LAST CDS_LIB pure_quanta
J 0
(-7275 1625);
DISPLAY INVISIBLE (-7275 1625);
FORCEPROP 1 LAST PATH I69
J 0
(-7325 1775);
DISPLAY 0.978723 (-7325 1775);
PAINT WHITE (-7325 1775);
DISPLAY INVISIBLE (-7325 1775);
FORCEADD OFFPAGE..2
R 2
(-7225 1425);
FORCEPROP 2 LAST $XR3 169 
J 0
(-7720 1389);
DISPLAY 0.638298 (-7720 1389);
PAINT MONO (-7720 1389);
FORCEPROP 2 LAST $XR2 172 
J 0
(-7600 1389);
DISPLAY 0.638298 (-7600 1389);
PAINT MONO (-7600 1389);
FORCEPROP 2 LAST $XR1 171 
J 0
(-7480 1389);
DISPLAY 0.638298 (-7480 1389);
PAINT MONO (-7480 1389);
FORCEPROP 2 LAST $XR0 170 
J 0
(-7480 1425);
DISPLAY 0.638298 (-7480 1425);
PAINT MONO (-7480 1425);
FORCEPROP 2 LAST CDS_LIB standard
J 0
(-7225 1425);
DISPLAY INVISIBLE (-7225 1425);
FORCEPROP 1 LAST OFFPAGE TRUE
J 2
(-7550 1300);
DISPLAY 0.872340 (-7550 1300);
PAINT GREEN (-7550 1300);
DISPLAY INVISIBLE (-7550 1300);
FORCEPROP 1 LAST COMMENT_BODY TRUE
J 2
(-7180 1330);
DISPLAY 0.872340 (-7180 1330);
PAINT GREEN (-7180 1330);
DISPLAY INVISIBLE (-7180 1330);
FORCEPROP 2 LAST PATH I70
J 0
(-7475 1475);
DISPLAY 1.021277 (-7475 1475);
DISPLAY INVISIBLE (-7475 1475);
FORCEADD UNIVERSAL_GND..1
(-7600 1450);
FORCEPROP 3 LASTPIN (-7600 1500) SIG_NAME GND\g
J 0
(-7590 1510);
DISPLAY 0.659574 (-7590 1510);
PAINT MONO (-7590 1510);
DISPLAY INVISIBLE (-7590 1510);
FORCEPROP 2 LAST CDS_LIB pure_quanta_power
J 0
(-7600 1450);
DISPLAY INVISIBLE (-7600 1450);
FORCEPROP 1 LAST PATH I71
J 0
(-7525 1450);
DISPLAY 0.872340 (-7525 1450);
PAINT AQUA (-7525 1450);
DISPLAY INVISIBLE (-7525 1450);
FORCEPROP 1 LAST HDL_POWER GND
J 1
(-7575 1375);
DISPLAY 0.872340 (-7575 1375);
PAINT GREEN (-7575 1375);
DISPLAY INVISIBLE (-7575 1375);
FORCEADD Q_CAP..1
(-7925 1650);
FORCEPROP 1 LAST LOCATION PC150_6
J 0
(-7875 1750);
DISPLAY 0.489362 (-7875 1750);
PAINT SKYBLUE (-7875 1750);
FORCEPROP 0 LAST $SEC 1
J 0
(-7875 1775);
DISPLAY 0.680851 (-7875 1775);
PAINT MONO (-7875 1775);
DISPLAY INVISIBLE (-7875 1775);
FORCEPROP 0 LAST CDS_SEC 1
J 0
(-7875 1775);
DISPLAY 1.021277 (-7875 1775);
DISPLAY INVISIBLE (-7875 1775);
FORCEPROP 1 LASTPIN (-7925 1750) $PN 1
J 0
(-7915 1730);
DISPLAY 0.489362 (-7915 1730);
PAINT MONO (-7915 1730);
FORCEPROP 1 LASTPIN (-7925 1550) $PN 2
J 0
(-7915 1530);
DISPLAY 0.489362 (-7915 1530);
PAINT MONO (-7915 1530);
FORCEPROP 1 LAST MATERIAL X7R
J 0
(-7875 1550);
DISPLAY 0.489362 (-7875 1550);
PAINT SKYBLUE (-7875 1550);
FORCEPROP 1 LAST TOLERANCE 10%
J 0
(-7875 1600);
DISPLAY 0.489362 (-7875 1600);
PAINT SKYBLUE (-7875 1600);
FORCEPROP 1 LAST VALUE 0.1UF
J 0
(-7875 1700);
DISPLAY 0.489362 (-7875 1700);
PAINT SKYBLUE (-7875 1700);
FORCEPROP 1 LAST PART_NUMBER CH4104K1B00
J 0
(-7875 1500);
DISPLAY 0.489362 (-7875 1500);
PAINT SKYBLUE (-7875 1500);
FORCEPROP 1 LAST VOLTAGE 25V
J 0
(-7875 1650);
DISPLAY 0.489362 (-7875 1650);
PAINT SKYBLUE (-7875 1650);
FORCEPROP 1 LAST PACK_TYPE 0402
J 0
(-7875 1450);
DISPLAY 0.489362 (-7875 1450);
PAINT SKYBLUE (-7875 1450);
FORCEPROP 2 LAST CDS_LIB pure_quanta
J 0
(-7925 1650);
DISPLAY INVISIBLE (-7925 1650);
FORCEPROP 1 LAST PATH I72
J 0
(-7875 1800);
DISPLAY 0.978723 (-7875 1800);
PAINT WHITE (-7875 1800);
DISPLAY INVISIBLE (-7875 1800);
FORCEADD UNIVERSAL_GND..1
(-5550 1200);
FORCEPROP 3 LASTPIN (-5550 1250) SIG_NAME GND\g
J 0
(-5540 1260);
DISPLAY 0.659574 (-5540 1260);
PAINT MONO (-5540 1260);
DISPLAY INVISIBLE (-5540 1260);
FORCEPROP 2 LAST CDS_LIB pure_quanta_power
J 0
(-5550 1200);
DISPLAY INVISIBLE (-5550 1200);
FORCEPROP 1 LAST PATH I73
J 0
(-5475 1200);
DISPLAY 0.872340 (-5475 1200);
PAINT AQUA (-5475 1200);
DISPLAY INVISIBLE (-5475 1200);
FORCEPROP 1 LAST HDL_POWER GND
J 1
(-5525 1125);
DISPLAY 0.872340 (-5525 1125);
PAINT GREEN (-5525 1125);
DISPLAY INVISIBLE (-5525 1125);
FORCEADD OFFPAGE..1
(-7200 1325);
FORCEPROP 2 LAST $XR0 169 
J 0
(-7452 1325);
DISPLAY 0.638298 (-7452 1325);
PAINT MONO (-7452 1325);
FORCEPROP 2 LAST CDS_LIB standard
J 2
(-7200 1325);
DISPLAY INVISIBLE (-7200 1325);
FORCEPROP 1 LAST OFFPAGE TRUE
J 0
(-6875 1200);
DISPLAY 0.872340 (-6875 1200);
PAINT GREEN (-6875 1200);
DISPLAY INVISIBLE (-6875 1200);
FORCEPROP 1 LAST COMMENT_BODY TRUE
J 0
(-7075 1225);
DISPLAY 0.872340 (-7075 1225);
PAINT GREEN (-7075 1225);
DISPLAY INVISIBLE (-7075 1225);
FORCEPROP 2 LAST PATH I74
J 0
(-7450 1375);
DISPLAY 1.021277 (-7450 1375);
DISPLAY INVISIBLE (-7450 1375);
FORCEADD UNIVERSAL_GND..1
(-7925 1375);
FORCEPROP 3 LASTPIN (-7925 1425) SIG_NAME GND\g
J 0
(-7915 1435);
DISPLAY 0.659574 (-7915 1435);
PAINT MONO (-7915 1435);
DISPLAY INVISIBLE (-7915 1435);
FORCEPROP 2 LAST CDS_LIB pure_quanta_power
J 0
(-7925 1375);
DISPLAY INVISIBLE (-7925 1375);
FORCEPROP 1 LAST PATH I75
J 0
(-7850 1375);
DISPLAY 0.872340 (-7850 1375);
PAINT AQUA (-7850 1375);
DISPLAY INVISIBLE (-7850 1375);
FORCEPROP 1 LAST HDL_POWER GND
J 1
(-7900 1300);
DISPLAY 0.872340 (-7900 1300);
PAINT GREEN (-7900 1300);
DISPLAY INVISIBLE (-7900 1300);
FORCEADD OFFPAGE..1
(-8150 1825);
FORCEPROP 2 LAST $XR5 175 
J 0
(-9032 1825);
DISPLAY 0.638298 (-9032 1825);
PAINT MONO (-9032 1825);
FORCEPROP 2 LAST $XR4 174 
J 0
(-8912 1825);
DISPLAY 0.638298 (-8912 1825);
PAINT MONO (-8912 1825);
FORCEPROP 2 LAST $XR3 172 
J 0
(-8792 1825);
DISPLAY 0.638298 (-8792 1825);
PAINT MONO (-8792 1825);
FORCEPROP 2 LAST $XR2 171 
J 0
(-8672 1825);
DISPLAY 0.638298 (-8672 1825);
PAINT MONO (-8672 1825);
FORCEPROP 2 LAST $XR1 170 
J 0
(-8552 1825);
DISPLAY 0.638298 (-8552 1825);
PAINT MONO (-8552 1825);
FORCEPROP 2 LAST $XR0 169 
J 0
(-8432 1825);
DISPLAY 0.638298 (-8432 1825);
PAINT MONO (-8432 1825);
FORCEPROP 2 LAST CDS_LIB standard
J 0
(-8150 1825);
DISPLAY INVISIBLE (-8150 1825);
FORCEPROP 1 LAST OFFPAGE TRUE
J 0
(-7825 1700);
DISPLAY 0.872340 (-7825 1700);
PAINT GREEN (-7825 1700);
DISPLAY INVISIBLE (-7825 1700);
FORCEPROP 1 LAST COMMENT_BODY TRUE
J 0
(-8025 1725);
DISPLAY 0.872340 (-8025 1725);
PAINT GREEN (-8025 1725);
DISPLAY INVISIBLE (-8025 1725);
FORCEPROP 2 LAST PATH I76
J 0
(-8425 1875);
DISPLAY 1.021277 (-8425 1875);
DISPLAY INVISIBLE (-8425 1875);
FORCEADD Q_CAP..1
(-4600 4475);
FORCEPROP 1 LAST LOCATION PC184
J 0
(-4550 4575);
DISPLAY 0.489362 (-4550 4575);
PAINT SKYBLUE (-4550 4575);
FORCEPROP 0 LAST $SEC 1
J 0
(-4550 4625);
DISPLAY 0.680851 (-4550 4625);
PAINT MONO (-4550 4625);
DISPLAY INVISIBLE (-4550 4625);
FORCEPROP 0 LAST CDS_SEC 1
J 0
(-4550 4625);
DISPLAY 1.021277 (-4550 4625);
DISPLAY INVISIBLE (-4550 4625);
FORCEPROP 1 LASTPIN (-4600 4575) $PN 1
J 0
(-4590 4555);
DISPLAY 0.489362 (-4590 4555);
PAINT MONO (-4590 4555);
FORCEPROP 1 LASTPIN (-4600 4375) $PN 2
J 0
(-4590 4355);
DISPLAY 0.489362 (-4590 4355);
PAINT MONO (-4590 4355);
FORCEPROP 1 LAST MATERIAL EMPTY
J 0
(-4550 4375);
DISPLAY 0.489362 (-4550 4375);
PAINT RED (-4550 4375);
FORCEPROP 1 LAST TOLERANCE 10%
J 0
(-4550 4425);
DISPLAY 0.489362 (-4550 4425);
PAINT SKYBLUE (-4550 4425);
FORCEPROP 1 LAST VALUE 560PF
J 0
(-4550 4525);
DISPLAY 0.489362 (-4550 4525);
PAINT SKYBLUE (-4550 4525);
FORCEPROP 1 LAST PART_NUMBER CH1566K1B09
J 0
(-4550 4325);
DISPLAY 0.489362 (-4550 4325);
PAINT SKYBLUE (-4550 4325);
FORCEPROP 1 LAST VOLTAGE 50V
J 0
(-4550 4475);
DISPLAY 0.489362 (-4550 4475);
PAINT SKYBLUE (-4550 4475);
FORCEPROP 1 LAST PACK_TYPE C0402
J 0
(-4550 4275);
DISPLAY 0.489362 (-4550 4275);
PAINT SKYBLUE (-4550 4275);
FORCEPROP 2 LAST CDS_LIB pure_quanta
J 0
(-4600 4475);
DISPLAY INVISIBLE (-4600 4475);
FORCEPROP 1 LAST PATH I77
J 0
(-4550 4625);
DISPLAY 0.978723 (-4550 4625);
PAINT WHITE (-4550 4625);
DISPLAY INVISIBLE (-4550 4625);
FORCEADD Q_RES..2
(-4600 4025);
FORCEPROP 1 LAST LOCATION PR501
J 0
(-4555 4150);
DISPLAY 0.489362 (-4555 4150);
PAINT SKYBLUE (-4555 4150);
FORCEPROP 0 LAST $SEC 1
J 0
(-4550 4200);
DISPLAY 0.680851 (-4550 4200);
PAINT MONO (-4550 4200);
DISPLAY INVISIBLE (-4550 4200);
FORCEPROP 0 LAST CDS_SEC 1
J 0
(-4550 4200);
DISPLAY 1.021277 (-4550 4200);
DISPLAY INVISIBLE (-4550 4200);
FORCEPROP 1 LASTPIN (-4600 4125) $PN 1
J 0
(-4595 4087);
DISPLAY 0.489362 (-4595 4087);
PAINT MONO (-4595 4087);
FORCEPROP 1 LASTPIN (-4600 3925) $PN 2
J 0
(-4595 3935);
DISPLAY 0.489362 (-4595 3935);
PAINT MONO (-4595 3935);
FORCEPROP 1 LAST WATTAGE 1/8W
J 0
(-4560 4000);
DISPLAY 0.489362 (-4560 4000);
PAINT SKYBLUE (-4560 4000);
FORCEPROP 1 LAST MATERIAL EMPTY
J 0
(-4560 3950);
DISPLAY 0.489362 (-4560 3950);
PAINT RED (-4560 3950);
FORCEPROP 1 LAST TOLERANCE 1%
J 0
(-4555 4050);
DISPLAY 0.489362 (-4555 4050);
PAINT SKYBLUE (-4555 4050);
FORCEPROP 1 LAST VALUE 1.5
J 0
(-4555 4100);
DISPLAY 0.489362 (-4555 4100);
PAINT SKYBLUE (-4555 4100);
FORCEPROP 1 LAST PART_NUMBER CS-1504FB00
J 0
(-4560 3900);
DISPLAY 0.489362 (-4560 3900);
PAINT SKYBLUE (-4560 3900);
FORCEPROP 1 LAST PACK_TYPE 0402LF
J 0
(-4560 3850);
DISPLAY 0.489362 (-4560 3850);
PAINT SKYBLUE (-4560 3850);
FORCEPROP 2 LAST CDS_LIB pure_quanta
J 0
(-4600 4025);
DISPLAY INVISIBLE (-4600 4025);
FORCEPROP 1 LAST PATH I78
J 0
(-4550 4200);
DISPLAY 0.978723 (-4550 4200);
PAINT WHITE (-4550 4200);
DISPLAY INVISIBLE (-4550 4200);
FORCEADD UNIVERSAL_GND..1
(-4600 3800);
FORCEPROP 3 LASTPIN (-4600 3850) SIG_NAME GND\g
J 0
(-4590 3860);
DISPLAY 0.659574 (-4590 3860);
PAINT MONO (-4590 3860);
DISPLAY INVISIBLE (-4590 3860);
FORCEPROP 2 LAST CDS_LIB pure_quanta_power
J 0
(-4600 3800);
DISPLAY INVISIBLE (-4600 3800);
FORCEPROP 1 LAST PATH I79
J 0
(-4525 3800);
DISPLAY 0.872340 (-4525 3800);
PAINT AQUA (-4525 3800);
DISPLAY INVISIBLE (-4525 3800);
FORCEPROP 1 LAST HDL_POWER GND
J 1
(-4575 3725);
DISPLAY 0.872340 (-4575 3725);
PAINT GREEN (-4575 3725);
DISPLAY INVISIBLE (-4575 3725);
FORCEADD OFFPAGE..2
R 2
(-7250 4650);
FORCEPROP 2 LAST $XR0 169 
J 0
(-7505 4650);
DISPLAY 0.638298 (-7505 4650);
PAINT MONO (-7505 4650);
FORCEPROP 2 LAST CDS_LIB standard
J 2
(-7250 4650);
DISPLAY INVISIBLE (-7250 4650);
FORCEPROP 1 LAST OFFPAGE TRUE
J 2
(-7575 4525);
DISPLAY 0.872340 (-7575 4525);
PAINT GREEN (-7575 4525);
DISPLAY INVISIBLE (-7575 4525);
FORCEPROP 1 LAST COMMENT_BODY TRUE
J 2
(-7205 4555);
DISPLAY 0.872340 (-7205 4555);
PAINT GREEN (-7205 4555);
DISPLAY INVISIBLE (-7205 4555);
FORCEPROP 2 LAST PATH I8
J 0
(-7200 4725);
DISPLAY 1.021277 (-7200 4725);
DISPLAY INVISIBLE (-7200 4725);
FORCEADD Q_CAP..1
(-4625 1750);
FORCEPROP 1 LAST LOCATION PC182
J 0
(-4575 1850);
DISPLAY 0.489362 (-4575 1850);
PAINT SKYBLUE (-4575 1850);
FORCEPROP 0 LAST $SEC 1
J 0
(-4575 1900);
DISPLAY 0.680851 (-4575 1900);
PAINT MONO (-4575 1900);
DISPLAY INVISIBLE (-4575 1900);
FORCEPROP 0 LAST CDS_SEC 1
J 0
(-4575 1900);
DISPLAY 1.021277 (-4575 1900);
DISPLAY INVISIBLE (-4575 1900);
FORCEPROP 1 LASTPIN (-4625 1850) $PN 1
J 0
(-4615 1830);
DISPLAY 0.489362 (-4615 1830);
PAINT MONO (-4615 1830);
FORCEPROP 1 LASTPIN (-4625 1650) $PN 2
J 0
(-4615 1630);
DISPLAY 0.489362 (-4615 1630);
PAINT MONO (-4615 1630);
FORCEPROP 1 LAST MATERIAL EMPTY
J 0
(-4575 1650);
DISPLAY 0.489362 (-4575 1650);
PAINT RED (-4575 1650);
FORCEPROP 1 LAST PART_NUMBER CH1566K1B09
J 0
(-4575 1600);
DISPLAY 0.489362 (-4575 1600);
PAINT SKYBLUE (-4575 1600);
FORCEPROP 1 LAST TOLERANCE 10%
J 0
(-4575 1700);
DISPLAY 0.489362 (-4575 1700);
PAINT SKYBLUE (-4575 1700);
FORCEPROP 1 LAST VALUE 560PF
J 0
(-4575 1800);
DISPLAY 0.489362 (-4575 1800);
PAINT SKYBLUE (-4575 1800);
FORCEPROP 1 LAST VOLTAGE 50V
J 0
(-4575 1750);
DISPLAY 0.489362 (-4575 1750);
PAINT SKYBLUE (-4575 1750);
FORCEPROP 1 LAST PACK_TYPE C0402
J 0
(-4575 1550);
DISPLAY 0.489362 (-4575 1550);
PAINT SKYBLUE (-4575 1550);
FORCEPROP 2 LAST CDS_LIB pure_quanta
J 0
(-4625 1750);
DISPLAY INVISIBLE (-4625 1750);
FORCEPROP 1 LAST PATH I80
J 0
(-4575 1900);
DISPLAY 0.978723 (-4575 1900);
PAINT WHITE (-4575 1900);
DISPLAY INVISIBLE (-4575 1900);
FORCEADD Q_RES..2
(-4625 1250);
FORCEPROP 1 LAST LOCATION PR500
J 0
(-4580 1375);
DISPLAY 0.489362 (-4580 1375);
PAINT SKYBLUE (-4580 1375);
FORCEPROP 0 LAST $SEC 1
J 0
(-4575 1425);
DISPLAY 0.680851 (-4575 1425);
PAINT MONO (-4575 1425);
DISPLAY INVISIBLE (-4575 1425);
FORCEPROP 0 LAST CDS_SEC 1
J 0
(-4575 1425);
DISPLAY 1.021277 (-4575 1425);
DISPLAY INVISIBLE (-4575 1425);
FORCEPROP 1 LASTPIN (-4625 1350) $PN 1
J 0
(-4620 1312);
DISPLAY 0.489362 (-4620 1312);
PAINT MONO (-4620 1312);
FORCEPROP 1 LASTPIN (-4625 1150) $PN 2
J 0
(-4620 1160);
DISPLAY 0.489362 (-4620 1160);
PAINT MONO (-4620 1160);
FORCEPROP 1 LAST PART_NUMBER CS-1504FB00
J 0
(-4585 1125);
DISPLAY 0.489362 (-4585 1125);
PAINT SKYBLUE (-4585 1125);
FORCEPROP 1 LAST WATTAGE 1/8W
J 0
(-4585 1225);
DISPLAY 0.489362 (-4585 1225);
PAINT SKYBLUE (-4585 1225);
FORCEPROP 1 LAST MATERIAL EMPTY
J 0
(-4585 1175);
DISPLAY 0.489362 (-4585 1175);
PAINT RED (-4585 1175);
FORCEPROP 1 LAST TOLERANCE 1%
J 0
(-4580 1275);
DISPLAY 0.489362 (-4580 1275);
PAINT SKYBLUE (-4580 1275);
FORCEPROP 1 LAST VALUE 1.5
J 0
(-4580 1325);
DISPLAY 0.489362 (-4580 1325);
PAINT SKYBLUE (-4580 1325);
FORCEPROP 1 LAST PACK_TYPE 0402LF
J 0
(-4585 1075);
DISPLAY 0.489362 (-4585 1075);
PAINT SKYBLUE (-4585 1075);
FORCEPROP 2 LAST CDS_LIB pure_quanta
J 0
(-4625 1250);
DISPLAY INVISIBLE (-4625 1250);
FORCEPROP 1 LAST PATH I81
J 0
(-4575 1425);
DISPLAY 0.978723 (-4575 1425);
PAINT WHITE (-4575 1425);
DISPLAY INVISIBLE (-4575 1425);
FORCEADD UNIVERSAL_GND..1
(-4625 1025);
FORCEPROP 3 LASTPIN (-4625 1075) SIG_NAME GND\g
J 0
(-4615 1085);
DISPLAY 0.659574 (-4615 1085);
PAINT MONO (-4615 1085);
DISPLAY INVISIBLE (-4615 1085);
FORCEPROP 2 LAST CDS_LIB pure_quanta_power
J 0
(-4625 1025);
DISPLAY INVISIBLE (-4625 1025);
FORCEPROP 1 LAST PATH I82
J 0
(-4550 1025);
DISPLAY 0.872340 (-4550 1025);
PAINT AQUA (-4550 1025);
DISPLAY INVISIBLE (-4550 1025);
FORCEPROP 1 LAST HDL_POWER GND
J 1
(-4600 950);
DISPLAY 0.872340 (-4600 950);
PAINT GREEN (-4600 950);
DISPLAY INVISIBLE (-4600 950);
FORCEADD VCC_CORE..1
(-7600 5900);
FORCEPROP 3 LASTPIN (-7600 5850) SIG_NAME PVDDCR_CPU0_P0_PVCC\g
J 0
(-7590 5860);
DISPLAY 0.659574 (-7590 5860);
PAINT MONO (-7590 5860);
DISPLAY INVISIBLE (-7590 5860);
FORCEPROP 1 LAST HDL_POWER PVDDCR_CPU0_P0_PVCC
J 1
(-7600 5950);
DISPLAY 0.489362 (-7600 5950);
PAINT GREEN (-7600 5950);
FORCEPROP 2 LAST CDS_LIB pure_quanta_power
J 0
(-7600 5900);
DISPLAY INVISIBLE (-7600 5900);
FORCEPROP 1 LAST PATH I83
J 0
(-7550 5925);
DISPLAY 0.872340 (-7550 5925);
PAINT AQUA (-7550 5925);
DISPLAY INVISIBLE (-7550 5925);
FORCEADD VCC_CORE..1
(-7600 3200);
FORCEPROP 3 LASTPIN (-7600 3150) SIG_NAME PVDDCR_CPU0_P0_PVCC\g
J 0
(-7590 3160);
DISPLAY 0.659574 (-7590 3160);
PAINT MONO (-7590 3160);
DISPLAY INVISIBLE (-7590 3160);
FORCEPROP 1 LAST HDL_POWER PVDDCR_CPU0_P0_PVCC
J 1
(-7600 3250);
DISPLAY 0.489362 (-7600 3250);
PAINT GREEN (-7600 3250);
FORCEPROP 2 LAST CDS_LIB pure_quanta_power
J 0
(-7600 3200);
DISPLAY INVISIBLE (-7600 3200);
FORCEPROP 1 LAST PATH I84
J 0
(-7550 3225);
DISPLAY 0.872340 (-7550 3225);
PAINT AQUA (-7550 3225);
DISPLAY INVISIBLE (-7550 3225);
FORCEADD UNIVERSAL_GND..1
(-4025 1575);
FORCEPROP 3 LASTPIN (-4025 1625) SIG_NAME GND\g
J 0
(-4015 1635);
DISPLAY 0.659574 (-4015 1635);
PAINT MONO (-4015 1635);
DISPLAY INVISIBLE (-4015 1635);
FORCEPROP 2 LAST CDS_LIB pure_quanta_power
J 0
(-4025 1575);
DISPLAY INVISIBLE (-4025 1575);
FORCEPROP 1 LAST PATH I85
J 0
(-3950 1575);
DISPLAY 0.872340 (-3950 1575);
PAINT AQUA (-3950 1575);
DISPLAY INVISIBLE (-3950 1575);
FORCEPROP 1 LAST HDL_POWER GND
J 1
(-4000 1500);
DISPLAY 0.872340 (-4000 1500);
PAINT GREEN (-4000 1500);
DISPLAY INVISIBLE (-4000 1500);
FORCEADD Q_INDUCTOR..1
(-3850 1700);
FORCEPROP 1 LAST LOCATION PL50
J 0
(-4000 1850);
DISPLAY 0.489362 (-4000 1850);
PAINT SKYBLUE (-4000 1850);
FORCEPROP 0 LAST $SEC 1
J 0
(-4000 1875);
DISPLAY 0.680851 (-4000 1875);
PAINT MONO (-4000 1875);
DISPLAY INVISIBLE (-4000 1875);
FORCEPROP 0 LAST CDS_SEC 1
J 0
(-4000 1875);
DISPLAY 0.680851 (-4000 1875);
DISPLAY INVISIBLE (-4000 1875);
FORCEPROP 0 LASTPIN (-3950 1675) $PN 1
J 2
(-3960 1685);
DISPLAY 0.489362 (-3960 1685);
PAINT MONO (-3960 1685);
FORCEPROP 0 LASTPIN (-3750 1675) $PN 2
J 0
(-3740 1685);
DISPLAY 0.489362 (-3740 1685);
PAINT MONO (-3740 1685);
FORCEPROP 1 LAST PART_NUMBER CV+22Y0EZ00
J 0
(-4000 1775);
DISPLAY 0.489362 (-4000 1775);
PAINT SKYBLUE (-4000 1775);
FORCEPROP 2 LAST PACK_TYPE SMLF
J 0
(-4000 1800);
DISPLAY 0.489362 (-4000 1800);
PAINT SKYBLUE (-4000 1800);
FORCEPROP 2 LAST VALUE 0.22UH/33A
J 0
(-4000 1825);
DISPLAY 0.489362 (-4000 1825);
PAINT SKYBLUE (-4000 1825);
FORCEPROP 1 LAST MATERIAL IND
J 0
(-4000 1750);
DISPLAY 0.489362 (-4000 1750);
PAINT SKYBLUE (-4000 1750);
FORCEPROP 1 LAST PATH I86
J 0
(-3775 1755);
DISPLAY 0.723404 (-3775 1755);
PAINT GREEN (-3775 1755);
DISPLAY INVISIBLE (-3775 1755);
FORCEPROP 1 LAST NEEDS_NO_SIZE TRUE
J 0
(-3850 1700);
DISPLAY 0.468085 (-3850 1700);
PAINT GREEN (-3850 1700);
DISPLAY INVISIBLE (-3850 1700);
FORCEPROP 2 LAST CDS_LIB pure_quanta
J 0
(-3850 1700);
DISPLAY INVISIBLE (-3850 1700);
FORCEADD DNS..1
(-4625 4475);
PAINT RED (-4625 4475);
FORCEPROP 2 LAST CDS_LIB mstr_misc
J 0
(-4625 4475);
DISPLAY INVISIBLE (-4625 4475);
FORCEPROP 1 LAST COMMENT_BODY TRUE
R 1
J 0
(-4550 4250);
DISPLAY 0.872340 (-4550 4250);
PAINT GREEN (-4550 4250);
DISPLAY INVISIBLE (-4550 4250);
FORCEADD DNS..1
(-4650 1750);
PAINT RED (-4650 1750);
FORCEPROP 2 LAST CDS_LIB mstr_misc
J 0
(-4650 1750);
DISPLAY INVISIBLE (-4650 1750);
FORCEPROP 1 LAST COMMENT_BODY TRUE
R 1
J 0
(-4575 1525);
DISPLAY 0.872340 (-4575 1525);
PAINT GREEN (-4575 1525);
DISPLAY INVISIBLE (-4575 1525);
FORCEADD DNS..1
(-4625 4025);
PAINT RED (-4625 4025);
FORCEPROP 2 LAST CDS_LIB mstr_misc
J 0
(-4625 4025);
DISPLAY INVISIBLE (-4625 4025);
FORCEPROP 1 LAST COMMENT_BODY TRUE
R 1
J 0
(-4550 3800);
DISPLAY 0.872340 (-4550 3800);
PAINT GREEN (-4550 3800);
DISPLAY INVISIBLE (-4550 3800);
FORCEADD DNS..1
(-7275 1600);
PAINT RED (-7275 1600);
FORCEPROP 2 LAST CDS_LIB mstr_misc
J 0
(-7275 1600);
DISPLAY INVISIBLE (-7275 1600);
FORCEPROP 1 LAST COMMENT_BODY TRUE
R 1
J 0
(-7200 1375);
DISPLAY 0.872340 (-7200 1375);
PAINT GREEN (-7200 1375);
DISPLAY INVISIBLE (-7200 1375);
FORCEADD DNS..1
(-7275 4325);
PAINT RED (-7275 4325);
FORCEPROP 2 LAST CDS_LIB mstr_misc
J 0
(-7275 4325);
DISPLAY INVISIBLE (-7275 4325);
FORCEPROP 1 LAST COMMENT_BODY TRUE
R 1
J 0
(-7200 4100);
DISPLAY 0.872340 (-7200 4100);
PAINT GREEN (-7200 4100);
DISPLAY INVISIBLE (-7200 4100);
FORCEADD QUANTA_TITLE_BLOCK_C..1
(0 0);
FORCEPROP 0 LAST CDS_CON_LAST_MODIFIED Fri Mar 11 14:53:25 2022
J 0
(-1885 15);
DISPLAY INVISIBLE (-1885 15);
FORCEPROP 1 LAST CUSTOM_TXT_CDS <CON_LAST_MODIFIED>
J 0
(-1885 15);
DISPLAY 0.978723 (-1885 15);
FORCEPROP 2 LAST CUSTOM_TXT_CDS <XR_PAGE_TITLE>
J 0
(-7890 5250);
DISPLAY 0.638298 (-7890 5250);
PAINT PINK (-7890 5250);
DISPLAY INVISIBLE (-7890 5250);
FORCEPROP 1 LAST CUSTOM_TXT_CDS <NAME_2>
J 0
(-3175 50);
FORCEPROP 1 LAST CUSTOM_TXT_CDS <NAME_1>
J 0
(-3175 175);
FORCEPROP 1 LAST CUSTOM_TXT_CDS <Q_NUMBER>
J 0
(-1403 103);
DISPLAY 1.212766 (-1403 103);
FORCEPROP 1 LAST CUSTOM_TXT_CDS <Q_PROJ>
J 0
(-2382 102);
DISPLAY 1.212766 (-2382 102);
FORCEPROP 1 LAST CUSTOM_TXT_CDS <Q_REV>
J 0
(-184 103);
DISPLAY 1.212766 (-184 103);
FORCEPROP 1 LAST CUSTOM_TXT_CDS <CON_PAGE_NUM> OF <CON_TOTAL_PAGES>
J 0
(-446 18);
DISPLAY 0.978723 (-446 18);
FORCEPROP 1 LAST Q_TITLE PVDDCR_CPU0_P0 VR PHASE 5&6
J 0
(-9325 50);
DISPLAY 2.446809 (-9325 50);
PAINT GREEN (-9325 50);
FORCEPROP 1 LAST Q_DEPT BU9
J 1
(-3763 49);
DISPLAY 1.957447 (-3763 49);
PAINT GREEN (-3763 49);
FORCEPROP 2 LAST PAGE_BORDER TRUE
J 0
(-7890 5250);
DISPLAY 0.638298 (-7890 5250);
PAINT PINK (-7890 5250);
DISPLAY INVISIBLE (-7890 5250);
FORCEPROP 1 LAST CDS_LMAN_SYM_OUTLINE -9475,6775,100,-125
J 0
(0 0);
DISPLAY 0.468085 (0 0);
PAINT GREEN (0 0);
DISPLAY INVISIBLE (0 0);
FORCEPROP 2 LAST CDS_LIB pure_quanta
J 0
(0 0);
DISPLAY INVISIBLE (0 0);
FORCEPROP 1 LAST COMMENT_BODY TRUE
J 0
(12 -13);
DISPLAY 0.978723 (12 -13);
PAINT GREEN (12 -13);
DISPLAY INVISIBLE (12 -13);
FORCEPROP 2 LAST CDS_XR_PAGE_TITLE CR-172 : @T6G_MB_LIB.T6G(SCH_1):PAGE172
J 0
(-7890 5250);
DISPLAY 0.638298 (-7890 5250);
PAINT PINK (-7890 5250);
DISPLAY INVISIBLE (-7890 5250);
FORCEADD DNS..1
(-4650 1250);
PAINT RED (-4650 1250);
FORCEPROP 2 LAST CDS_LIB mstr_misc
J 0
(-4650 1250);
DISPLAY INVISIBLE (-4650 1250);
FORCEPROP 1 LAST COMMENT_BODY TRUE
R 1
J 0
(-4575 1025);
DISPLAY 0.872340 (-4575 1025);
PAINT GREEN (-4575 1025);
DISPLAY INVISIBLE (-4575 1025);
WIRE 16 -1 (-7925 4275)(-7925 4150);
WIRE 16 -1 (-7600 4900)(-7600 4850);
WIRE 16 -1 (-7250 5400)(-7250 5300);
WIRE 16 -1 (-7375 4350)(-7600 4350);
WIRE 16 -1 (-7600 4350)(-7600 4225);
WIRE 16 -1 (-7250 2700)(-7250 2575);
WIRE 16 -1 (-7600 2175)(-7600 2125);
WIRE 16 -1 (-7375 1625)(-7600 1625);
WIRE 16 -1 (-7600 1625)(-7600 1500);
WIRE 16 -1 (-7925 1550)(-7925 1425);
WIRE 16 -1 (-4600 3925)(-4600 3850);
WIRE 16 -1 (-4625 1150)(-4625 1075);
WIRE 16 -1 (-4575 2275)(-3675 2275);
FORCEPROP 2 LAST SIG_NAME SW_PVDDCR_CPU0_P0_BOOT6_RC
J 2
(-3710 2285);
DISPLAY 0.489362 (-3710 2285);
FORCEPROP 2 LASTPROP $XRERR UNIQUE?
J 0
(-3950 2285);
DISPLAY 0.638298 (-3950 2285);
PAINT MONO (-3950 2285);
DISPLAY INVISIBLE (-3950 2285);
WIRE 16 -1 (-3675 2275)(-3675 2250);
WIRE 16 -1 (-3675 2050)(-3675 2025);
WIRE 16 -1 (-3675 2025)(-5700 2025);
FORCEPROP 2 LAST SIG_NAME SW_PVDDCR_CPU0_P0_PH6
J 0
(-5585 2035);
DISPLAY 0.489362 (-5585 2035);
FORCEPROP 2 LASTPROP $XRERR UNIQUE?
J 0
(-5825 2035);
DISPLAY 0.638298 (-5825 2035);
PAINT MONO (-5825 2035);
DISPLAY INVISIBLE (-5825 2035);
WIRE 16 -1 (-4625 1925)(-3275 1925);
WIRE 16 -1 (-4625 1925)(-4625 1850);
WIRE 16 -1 (-5700 1925)(-4625 1925);
FORCEPROP 2 LAST SIG_NAME SW_PVDDCR_CPU0_P0_SW6
J 0
(-5585 1935);
DISPLAY 0.489362 (-5585 1935);
FORCEPROP 2 LASTPROP $XRERR UNIQUE?
J 0
(-5825 1935);
DISPLAY 0.638298 (-5825 1935);
PAINT MONO (-5825 1935);
DISPLAY INVISIBLE (-5825 1935);
WIRE 16 -1 (-3950 5425)(-3950 5300);
WIRE 16 -1 (-3950 5300)(-3950 5225);
WIRE 16 -1 (-4300 5300)(-3950 5300);
WIRE 16 -1 (-4300 5425)(-4300 5300);
WIRE 16 -1 (-4650 5300)(-4300 5300);
WIRE 16 -1 (-4650 5425)(-4650 5300);
WIRE 16 -1 (-4975 5300)(-4650 5300);
WIRE 16 -1 (-4975 5425)(-4975 5300);
WIRE 16 -1 (-5350 5300)(-4975 5300);
WIRE 16 -1 (-5350 5425)(-5350 5300);
WIRE 16 -1 (-1475 4375)(-1475 4250);
WIRE 16 -1 (-1050 4250)(-1475 4250);
WIRE 16 -1 (-1050 4375)(-1050 4250);
WIRE 16 -1 (-1050 4175)(-1050 4250);
WIRE 16 -1 (-2475 4400)(-2025 4400);
FORCEPROP 2 LAST SIG_NAME IND_CPU0_P0_CPL5
J 0
(-2385 4410);
DISPLAY 0.489362 (-2385 4410);
WIRE 16 -1 (-3725 4400)(-3275 4400);
FORCEPROP 2 LAST SIG_NAME IND_CPU0_P0_CPL6
J 0
(-3710 4410);
DISPLAY 0.489362 (-3710 4410);
WIRE 16 -1 (-4575 5000)(-3675 5000);
FORCEPROP 2 LAST SIG_NAME SW_PVDDCR_CPU0_P0_BOOT5_RC
J 2
(-3710 5010);
DISPLAY 0.489362 (-3710 5010);
FORCEPROP 2 LASTPROP $XRERR UNIQUE?
J 0
(-3950 5010);
DISPLAY 0.638298 (-3950 5010);
PAINT MONO (-3950 5010);
DISPLAY INVISIBLE (-3950 5010);
WIRE 16 -1 (-3675 5000)(-3675 4975);
WIRE 16 -1 (-3675 4775)(-3675 4750);
WIRE 16 -1 (-3675 4750)(-5700 4750);
FORCEPROP 2 LAST SIG_NAME SW_PVDDCR_CPU0_P0_PH5
J 0
(-5585 4760);
DISPLAY 0.489362 (-5585 4760);
FORCEPROP 2 LASTPROP $XRERR UNIQUE?
J 0
(-5825 4760);
DISPLAY 0.638298 (-5825 4760);
PAINT MONO (-5825 4760);
DISPLAY INVISIBLE (-5825 4760);
WIRE 16 -1 (-1475 1650)(-1475 1525);
WIRE 16 -1 (-1050 1525)(-1475 1525);
WIRE 16 -1 (-1050 1450)(-1050 1525);
WIRE 16 -1 (-1050 1650)(-1050 1525);
WIRE 16 -1 (-2475 1675)(-2000 1675);
FORCEPROP 2 LAST SIG_NAME IND_CPU0_P0_CPL6
J 0
(-2385 1685);
DISPLAY 0.489362 (-2385 1685);
WIRE 16 -1 (-5700 4650)(-4600 4650);
FORCEPROP 2 LAST SIG_NAME SW_PVDDCR_CPU0_P0_SW5
J 0
(-5585 4660);
DISPLAY 0.489362 (-5585 4660);
FORCEPROP 2 LASTPROP $XRERR UNIQUE?
J 0
(-5825 4660);
DISPLAY 0.638298 (-5825 4660);
PAINT MONO (-5825 4660);
DISPLAY INVISIBLE (-5825 4660);
WIRE 16 -1 (-4600 4650)(-3275 4650);
WIRE 16 -1 (-4600 4650)(-4600 4575);
WIRE 16 -1 (-4600 4375)(-4600 4125);
FORCEPROP 2 LAST SIG_NAME SW_PVDDCR_CPU0_P0_SW5_RC
J 0
(-4560 4210);
DISPLAY 0.489362 (-4560 4210);
FORCEPROP 2 LASTPROP $XRERR UNIQUE?
J 0
(-4800 4210);
DISPLAY 0.638298 (-4800 4210);
PAINT MONO (-4800 4210);
DISPLAY INVISIBLE (-4800 4210);
WIRE 16 -1 (-5700 5000)(-4775 5000);
FORCEPROP 2 LAST SIG_NAME SW_PVDDCR_CPU0_P0_BOOT5
J 0
(-5585 5010);
DISPLAY 0.489362 (-5585 5010);
FORCEPROP 2 LASTPROP $XRERR UNIQUE?
J 0
(-5825 5010);
DISPLAY 0.638298 (-5825 5010);
PAINT MONO (-5825 5010);
DISPLAY INVISIBLE (-5825 5010);
WIRE 16 -1 (-5600 5300)(-5600 5250);
WIRE 16 -1 (-5700 5300)(-5600 5300);
WIRE 16 -1 (-5600 5700)(-5600 5300);
WIRE 16 -1 (-5600 5250)(-5700 5250);
WIRE 16 -1 (-5600 5700)(-5350 5700);
WIRE 16 -1 (-5350 5625)(-5350 5700);
WIRE 16 -1 (-5350 5700)(-4975 5700);
WIRE 16 -1 (-4975 5700)(-4650 5700);
WIRE 16 -1 (-4975 5625)(-4975 5700);
WIRE 16 -1 (-4650 5625)(-4650 5700);
WIRE 16 -1 (-4650 5700)(-4300 5700);
WIRE 16 -1 (-4300 5700)(-3950 5700);
WIRE 16 -1 (-4300 5700)(-4300 5625);
WIRE 16 -1 (-3950 5775)(-3950 5700);
WIRE 16 -1 (-3950 5700)(-3950 5625);
WIRE 16 -1 (-5700 4300)(-5175 4300);
FORCEPROP 2 LAST SIG_NAME NC_PVDDCR_CPU0_P0_GL2_5
J 0
(-5585 4310);
DISPLAY 0.489362 (-5585 4310);
FORCEPROP 2 LASTPROP $XRERR UNIQUE?
J 0
(-5145 4300);
DISPLAY 0.638298 (-5145 4300);
PAINT MONO (-5145 4300);
DISPLAY INVISIBLE (-5145 4300);
WIRE 16 -1 (-5700 4350)(-5175 4350);
FORCEPROP 2 LAST SIG_NAME NC_PVDDCR_CPU0_P0_GL1_5
J 0
(-5585 4360);
DISPLAY 0.489362 (-5585 4360);
FORCEPROP 2 LASTPROP $XRERR UNIQUE?
J 0
(-5145 4350);
DISPLAY 0.638298 (-5145 4350);
PAINT MONO (-5145 4350);
DISPLAY INVISIBLE (-5145 4350);
WIRE 16 -1 (-6550 4400)(-7000 4400);
FORCEPROP 2 LAST SIG_NAME NC_PVDDCR_CPU0_P0_DNC5
J 2
(-6610 4410);
DISPLAY 0.489362 (-6610 4410);
FORCEPROP 2 LASTPROP $XRERR UNIQUE?
J 0
(-7240 4400);
DISPLAY 0.638298 (-7240 4400);
PAINT MONO (-7240 4400);
DISPLAY INVISIBLE (-7240 4400);
WIRE 16 -1 (-6550 4650)(-7200 4650);
FORCEPROP 2 LAST SIG_NAME PVDDCR_CPU0_P0_IMON5
J 2
(-6610 4660);
DISPLAY 0.489362 (-6610 4660);
WIRE 16 -1 (-6550 4150)(-7175 4150);
FORCEPROP 2 LAST SIG_NAME PVDDCR_CPU0_P0_TEMP0
J 2
(-6610 4160);
DISPLAY 0.489362 (-6610 4160);
WIRE 16 -1 (-7175 4350)(-6550 4350);
FORCEPROP 2 LAST SIG_NAME PVDDCR_CPU0_P0_LSET5
J 2
(-6610 4360);
DISPLAY 0.489362 (-6610 4360);
FORCEPROP 2 LASTPROP $XRERR UNIQUE?
J 0
(-6850 4360);
DISPLAY 0.638298 (-6850 4360);
PAINT MONO (-6850 4360);
DISPLAY INVISIBLE (-6850 4360);
WIRE 16 -1 (-8100 4550)(-7925 4550);
WIRE 16 -1 (-6550 4550)(-7925 4550);
FORCEPROP 2 LAST SIG_NAME PVDDCR_CPU0_P0_VCCS
J 2
(-6610 4560);
DISPLAY 0.489362 (-6610 4560);
WIRE 16 -1 (-7925 4475)(-7925 4550);
WIRE 16 -1 (-7150 5175)(-7600 5175);
WIRE 16 -1 (-7150 5175)(-7150 5000);
FORCEPROP 2 LAST SIG_NAME PVDDCR_CPU0_P0_VCC5
J 2
(-6660 5010);
DISPLAY 0.489362 (-6660 5010);
FORCEPROP 2 LASTPROP $XRERR UNIQUE?
J 0
(-6900 5010);
DISPLAY 0.638298 (-6900 5010);
PAINT MONO (-6900 5010);
DISPLAY INVISIBLE (-6900 5010);
WIRE 16 -1 (-7600 5400)(-7600 5175);
WIRE 16 -1 (-7600 5175)(-7600 5100);
WIRE 16 -1 (-7150 5000)(-6550 5000);
WIRE 16 -1 (-7150 5000)(-7150 4800);
WIRE 16 -1 (-7150 4800)(-6550 4800);
WIRE 16 -1 (-7600 5600)(-7600 5725);
WIRE 16 -1 (-7250 5725)(-7600 5725);
WIRE 16 -1 (-7600 5850)(-7600 5725);
WIRE 16 -1 (-7250 5600)(-7250 5725);
WIRE 16 -1 (-6850 5725)(-7250 5725);
WIRE 16 -1 (-6850 5300)(-6850 5725);
WIRE 16 -1 (-6850 5300)(-6550 5300);
WIRE 16 -1 (-5700 4050)(-5550 4050);
WIRE 16 -1 (-5550 4050)(-5550 4100);
WIRE 16 -1 (-5550 3975)(-5550 4050);
WIRE 16 -1 (-5550 4100)(-5550 4150);
WIRE 16 -1 (-5700 4100)(-5550 4100);
WIRE 16 -1 (-5700 4150)(-5550 4150);
WIRE 16 -1 (-5550 4200)(-5550 4150);
WIRE 16 -1 (-5550 4200)(-5700 4200);
WIRE 16 -1 (-5350 2700)(-5350 2575);
WIRE 16 -1 (-5350 2575)(-4975 2575);
WIRE 16 -1 (-4975 2575)(-4650 2575);
WIRE 16 -1 (-4975 2700)(-4975 2575);
WIRE 16 -1 (-4650 2575)(-4325 2575);
WIRE 16 -1 (-4650 2700)(-4650 2575);
WIRE 16 -1 (-4025 2575)(-4325 2575);
WIRE 16 -1 (-4325 2700)(-4325 2575);
WIRE 16 -1 (-4025 2700)(-4025 2575);
WIRE 16 -1 (-4025 2575)(-4025 2500);
WIRE 16 -1 (-5700 2275)(-4775 2275);
FORCEPROP 2 LAST SIG_NAME SW_PVDDCR_CPU0_P0_BOOT6
J 0
(-5585 2285);
DISPLAY 0.489362 (-5585 2285);
FORCEPROP 2 LASTPROP $XRERR UNIQUE?
J 0
(-5825 2285);
DISPLAY 0.638298 (-5825 2285);
PAINT MONO (-5825 2285);
DISPLAY INVISIBLE (-5825 2285);
WIRE 16 -1 (-5600 2575)(-5600 2525);
WIRE 16 -1 (-5700 2575)(-5600 2575);
WIRE 16 -1 (-5600 2975)(-5600 2575);
WIRE 16 -1 (-5600 2525)(-5700 2525);
WIRE 16 -1 (-5600 2975)(-5350 2975);
WIRE 16 -1 (-5350 2975)(-4975 2975);
WIRE 16 -1 (-5350 2900)(-5350 2975);
WIRE 16 -1 (-4975 2975)(-4650 2975);
WIRE 16 -1 (-4975 2900)(-4975 2975);
WIRE 16 -1 (-4650 2975)(-4325 2975);
WIRE 16 -1 (-4650 2900)(-4650 2975);
WIRE 16 -1 (-4325 2975)(-4025 2975);
WIRE 16 -1 (-4325 2975)(-4325 2900);
WIRE 16 -1 (-4025 3050)(-4025 2975);
WIRE 16 -1 (-4025 2975)(-4025 2900);
WIRE 16 -1 (-4625 1650)(-4625 1350);
FORCEPROP 2 LAST SIG_NAME SW_PVDDCR_CPU0_P0_SW6_RC
J 0
(-4585 1460);
DISPLAY 0.489362 (-4585 1460);
FORCEPROP 2 LASTPROP $XRERR UNIQUE?
J 0
(-4825 1460);
DISPLAY 0.638298 (-4825 1460);
PAINT MONO (-4825 1460);
DISPLAY INVISIBLE (-4825 1460);
WIRE 16 -1 (-5700 1675)(-4950 1675);
WIRE 16 -1 (-4950 875)(-4950 1675);
WIRE 16 -1 (-4400 875)(-4950 875);
FORCEPROP 2 LAST SIG_NAME PVDDCR_CPU0_P0_VOS6
J 0
(-5585 1700);
DISPLAY 0.489362 (-5585 1700);
FORCEPROP 2 LASTPROP $XRERR UNIQUE?
J 0
(-5825 1700);
DISPLAY 0.638298 (-5825 1700);
PAINT MONO (-5825 1700);
DISPLAY INVISIBLE (-5825 1700);
WIRE 16 -1 (-5700 1325)(-5550 1325);
WIRE 16 -1 (-5550 1325)(-5550 1375);
WIRE 16 -1 (-5550 1250)(-5550 1325);
WIRE 16 -1 (-5700 1375)(-5550 1375);
WIRE 16 -1 (-5550 1375)(-5550 1425);
WIRE 16 -1 (-5700 1425)(-5550 1425);
WIRE 16 -1 (-5550 1475)(-5550 1425);
WIRE 16 -1 (-5550 1475)(-5700 1475);
WIRE 16 -1 (-5700 1575)(-5175 1575);
FORCEPROP 2 LAST SIG_NAME NC_PVDDCR_CPU0_P0_GL2_6
J 0
(-5585 1585);
DISPLAY 0.489362 (-5585 1585);
FORCEPROP 2 LASTPROP $XRERR UNIQUE?
J 0
(-5145 1575);
DISPLAY 0.638298 (-5145 1575);
PAINT MONO (-5145 1575);
DISPLAY INVISIBLE (-5145 1575);
WIRE 16 -1 (-5700 1625)(-5175 1625);
FORCEPROP 2 LAST SIG_NAME NC_PVDDCR_CPU0_P0_GL1_6
J 0
(-5585 1635);
DISPLAY 0.489362 (-5585 1635);
FORCEPROP 2 LASTPROP $XRERR UNIQUE?
J 0
(-5145 1625);
DISPLAY 0.638298 (-5145 1625);
PAINT MONO (-5145 1625);
DISPLAY INVISIBLE (-5145 1625);
WIRE 16 -1 (-6550 4050)(-7150 4050);
FORCEPROP 2 LAST SIG_NAME PVDDCR_CPU0_P0_PWM5
J 2
(-6610 4060);
DISPLAY 0.489362 (-6610 4060);
WIRE 16 -1 (-7600 2450)(-7150 2450);
WIRE 16 -1 (-7600 2675)(-7600 2450);
WIRE 16 -1 (-7600 2450)(-7600 2375);
WIRE 16 -1 (-7150 2450)(-7150 2275);
FORCEPROP 2 LAST SIG_NAME PVDDCR_CPU0_P0_VCC6
J 2
(-6660 2285);
DISPLAY 0.489362 (-6660 2285);
FORCEPROP 2 LASTPROP $XRERR UNIQUE?
J 0
(-6900 2285);
DISPLAY 0.638298 (-6900 2285);
PAINT MONO (-6900 2285);
DISPLAY INVISIBLE (-6900 2285);
WIRE 16 -1 (-7150 2275)(-6550 2275);
WIRE 16 -1 (-7150 2275)(-7150 2075);
WIRE 16 -1 (-7150 2075)(-6550 2075);
WIRE 16 -1 (-7600 2875)(-7600 3000);
WIRE 16 -1 (-7600 3150)(-7600 3000);
WIRE 16 -1 (-7250 3000)(-7600 3000);
WIRE 16 -1 (-6875 3000)(-7250 3000);
WIRE 16 -1 (-7250 2900)(-7250 3000);
WIRE 16 -1 (-6875 2575)(-6875 3000);
WIRE 16 -1 (-6875 2575)(-6550 2575);
WIRE 16 -1 (-6550 1325)(-7150 1325);
FORCEPROP 2 LAST SIG_NAME PVDDCR_CPU0_P0_PWM6
J 2
(-6610 1335);
DISPLAY 0.489362 (-6610 1335);
WIRE 16 -1 (-6550 1675)(-7000 1675);
FORCEPROP 2 LAST SIG_NAME NC_PVDDCR_CPU0_P0_DNC6
J 2
(-6610 1685);
DISPLAY 0.489362 (-6610 1685);
FORCEPROP 2 LASTPROP $XRERR UNIQUE?
J 0
(-7240 1675);
DISPLAY 0.638298 (-7240 1675);
PAINT MONO (-7240 1675);
DISPLAY INVISIBLE (-7240 1675);
WIRE 16 -1 (-6550 1425)(-7175 1425);
FORCEPROP 2 LAST SIG_NAME PVDDCR_CPU0_P0_TEMP0
J 2
(-6610 1435);
DISPLAY 0.489362 (-6610 1435);
WIRE 16 -1 (-6550 1925)(-7200 1925);
FORCEPROP 2 LAST SIG_NAME PVDDCR_CPU0_P0_IMON6
J 2
(-6610 1935);
DISPLAY 0.489362 (-6610 1935);
WIRE 16 -1 (-7175 1625)(-6550 1625);
FORCEPROP 2 LAST SIG_NAME PVDDCR_CPU0_P0_LSET6
J 2
(-6610 1635);
DISPLAY 0.489362 (-6610 1635);
FORCEPROP 2 LASTPROP $XRERR UNIQUE?
J 0
(-6850 1635);
DISPLAY 0.638298 (-6850 1635);
PAINT MONO (-6850 1635);
DISPLAY INVISIBLE (-6850 1635);
WIRE 16 -1 (-8100 1825)(-7925 1825);
WIRE 16 -1 (-6550 1825)(-7925 1825);
FORCEPROP 2 LAST SIG_NAME PVDDCR_CPU0_P0_VCCS
J 2
(-6610 1835);
DISPLAY 0.489362 (-6610 1835);
WIRE 16 -1 (-7925 1750)(-7925 1825);
WIRE 16 -1 (-4125 3700)(-4950 3700);
FORCEPROP 2 LAST SIG_NAME PVDDCR_CPU0_P0_VOS5
J 0
(-5585 4425);
DISPLAY 0.489362 (-5585 4425);
FORCEPROP 2 LASTPROP $XRERR UNIQUE?
J 0
(-5825 4425);
DISPLAY 0.638298 (-5825 4425);
PAINT MONO (-5825 4425);
DISPLAY INVISIBLE (-5825 4425);
WIRE 16 -1 (-4950 3700)(-4950 4400);
WIRE 16 -1 (-5700 4400)(-4950 4400);
WIRE 16 -1 (-1700 4650)(-1700 3700);
WIRE 16 -1 (-1700 4650)(-1475 4650);
WIRE 16 -1 (-2475 4650)(-1700 4650);
WIRE 16 -1 (-1700 3700)(-3925 3700);
WIRE 16 -1 (-1475 4650)(-1050 4650);
WIRE 16 -1 (-1475 4650)(-1475 4575);
WIRE 16 -1 (-1050 4750)(-1050 4650);
WIRE 16 -1 (-1050 4650)(-1050 4575);
WIRE 16 -1 (-4025 1625)(-4025 1675);
WIRE 16 -1 (-4025 1675)(-3950 1675);
WIRE 16 -1 (-1700 1925)(-1700 875);
WIRE 16 -1 (-2475 1925)(-1700 1925);
WIRE 16 -1 (-1700 1925)(-1475 1925);
WIRE 16 -1 (-1700 875)(-4200 875);
WIRE 16 -1 (-1475 1925)(-1050 1925);
WIRE 16 -1 (-1475 1925)(-1475 1850);
WIRE 16 -1 (-1050 2025)(-1050 1925);
WIRE 16 -1 (-1050 1925)(-1050 1850);
WIRE 16 -1 (-3750 1675)(-3275 1675);
FORCEPROP 2 LAST SIG_NAME IND_CPU0_P0_CPL0
J 0
(-3735 1685);
DISPLAY 0.489362 (-3735 1685);
FORCEPROP 2 LASTPROP $XRERR UNIQUE?
J 0
(-3975 1685);
DISPLAY 0.638298 (-3975 1685);
PAINT MONO (-3975 1685);
DISPLAY INVISIBLE (-3975 1685);
DOT 1 (-5550 4150);
DOT 1 (-4650 2975);
DOT 1 (-5550 1325);
DOT 1 (-4325 2575);
DOT 1 (-4975 2975);
DOT 1 (-5350 2975);
DOT 1 (-7925 1825);
DOT 1 (-5550 1375);
DOT 1 (-5550 4100);
DOT 1 (-1050 4650);
DOT 1 (-4300 5300);
DOT 1 (-4300 5700);
DOT 1 (-3950 5300);
DOT 1 (-3950 5700);
DOT 1 (-7600 3000);
DOT 1 (-7250 3000);
DOT 1 (-7150 5000);
DOT 1 (-7250 5725);
DOT 1 (-7600 5725);
DOT 1 (-7600 5175);
DOT 1 (-1700 1925);
DOT 1 (-7600 2450);
DOT 1 (-4650 2575);
DOT 1 (-1475 4650);
DOT 1 (-1050 4250);
DOT 1 (-1700 4650);
DOT 1 (-4650 5700);
DOT 1 (-4975 5700);
DOT 1 (-4650 5300);
DOT 1 (-4975 5300);
DOT 1 (-5350 5700);
DOT 1 (-5600 5300);
DOT 1 (-7925 4550);
DOT 1 (-5550 4050);
DOT 1 (-1050 1925);
DOT 1 (-1475 1925);
DOT 1 (-1050 1525);
DOT 1 (-4025 2975);
DOT 1 (-5600 2575);
DOT 1 (-5550 1425);
DOT 1 (-7150 2275);
DOT 1 (-4975 2575);
DOT 1 (-4600 4650);
DOT 1 (-4025 2575);
DOT 1 (-4325 2975);
DOT 1 (-4625 1925);
FORCENOTE
PVDDCR_CPU0_P0_PHASE5
(-6700 6050) 0;
DISPLAY LEFT (-6700 6050);
DISPLAY 1.595745 (-6700 6050);
PAINT WHITE (-6700 6050);
FORCENOTE
PVDDCR_CPU0_P0_PHASE6
(-6700 3325) 0;
DISPLAY LEFT (-6700 3325);
DISPLAY 1.595745 (-6700 3325);
PAINT WHITE (-6700 3325);
FORCENOTE
2ND=CV+15^0TZ01
(-2425 4700) 0;
DISPLAY LEFT (-2425 4700);
DISPLAY 0.638298 (-2425 4700);
PAINT WHITE (-2425 4700);
FORCENOTE
DCR=1-4,0.105M OHM
(-2425 4800) 0;
DISPLAY LEFT (-2425 4800);
DISPLAY 0.638298 (-2425 4800);
PAINT WHITE (-2425 4800);
FORCENOTE
PGL6303.151HLT
(-2425 4950) 0;
DISPLAY LEFT (-2425 4950);
DISPLAY 0.638298 (-2425 4950);
PAINT WHITE (-2425 4950);
FORCENOTE
DCR=2-3,0.27M OHM
(-2425 4750) 0;
DISPLAY LEFT (-2425 4750);
DISPLAY 0.638298 (-2425 4750);
PAINT WHITE (-2425 4750);
FORCENOTE
11.0*7.5*12.5
(-2425 4850) 0;
DISPLAY LEFT (-2425 4850);
DISPLAY 0.638298 (-2425 4850);
PAINT WHITE (-2425 4850);
FORCENOTE
ISAT:70A@100C
(-2425 4900) 0;
DISPLAY LEFT (-2425 4900);
DISPLAY 0.638298 (-2425 4900);
PAINT WHITE (-2425 4900);
FORCENOTE
ISAT:70A@100C
(-2425 2200) 0;
DISPLAY LEFT (-2425 2200);
DISPLAY 0.638298 (-2425 2200);
PAINT WHITE (-2425 2200);
FORCENOTE
PGL6303.151HLT
(-2425 2250) 0;
DISPLAY LEFT (-2425 2250);
DISPLAY 0.638298 (-2425 2250);
PAINT WHITE (-2425 2250);
FORCENOTE
11.0*7.5*12.5
(-2425 2150) 0;
DISPLAY LEFT (-2425 2150);
DISPLAY 0.638298 (-2425 2150);
PAINT WHITE (-2425 2150);
FORCENOTE
DCR=1-4,0.105M OHM
(-2425 2100) 0;
DISPLAY LEFT (-2425 2100);
DISPLAY 0.638298 (-2425 2100);
PAINT WHITE (-2425 2100);
FORCENOTE
2ND=CV+15^0TZ01
(-2425 2000) 0;
DISPLAY LEFT (-2425 2000);
DISPLAY 0.638298 (-2425 2000);
PAINT WHITE (-2425 2000);
FORCENOTE
DCR=2-3,0.27M OHM
(-2425 2050) 0;
DISPLAY LEFT (-2425 2050);
DISPLAY 0.638298 (-2425 2050);
PAINT WHITE (-2425 2050);
FORCENOTE
HCME656510Q-221QL
(-3900 1600) 0;
DISPLAY LEFT (-3900 1600);
DISPLAY 0.638298 (-3900 1600);
PAINT WHITE (-3900 1600);
FORCENOTE
ISAT:30A@100C
(-3900 1550) 0;
DISPLAY LEFT (-3900 1550);
DISPLAY 0.638298 (-3900 1550);
PAINT WHITE (-3900 1550);
FORCENOTE
6.5*6.5*10.0
(-3900 1500) 0;
DISPLAY LEFT (-3900 1500);
DISPLAY 0.638298 (-3900 1500);
PAINT WHITE (-3900 1500);
FORCENOTE
DCR=0.17M OHM
(-3900 1450) 0;
DISPLAY LEFT (-3900 1450);
DISPLAY 0.638298 (-3900 1450);
PAINT WHITE (-3900 1450);
FORCENOTE
2ND=CV+22Y0EZ01
(-3900 1400) 0;
DISPLAY LEFT (-3900 1400);
DISPLAY 0.638298 (-3900 1400);
PAINT WHITE (-3900 1400);
QUIT
